FILE_TYPE = MACRO_DRAWING;
SET COLOR_WIRE YELLOW;
SET COLOR_PROP ORANGE;
SET COLOR_DOT WHITE;
SET COLOR_ARC YELLOW;
SET COLOR_BODY GREEN;
SET COLOR_NOTE PURPLE;
SET PROP_DISPLAY VALUE;
SET PAGE_NUMBER P265;
FORCEADD UNIVERSAL_GND..1
(-9050 1950);
FORCEPROP 3 LASTPIN (-9050 2000) SIG_NAME T1_GND\g
J 0
(-9040 2010);
DISPLAY 0.659574 (-9040 2010);
PAINT MONO (-9040 2010);
DISPLAY INVISIBLE (-9040 2010);
FORCEPROP 1 LAST HDL_POWER T1_GND
J 1
(-9025 1875);
DISPLAY 0.872340 (-9025 1875);
PAINT GREEN (-9025 1875);
FORCEPROP 2 LAST CDS_LIB pure_quanta_power
J 0
(-9050 1950);
DISPLAY INVISIBLE (-9050 1950);
FORCEPROP 1 LAST PATH I1
J 0
(-8975 1950);
DISPLAY 0.872340 (-8975 1950);
PAINT AQUA (-8975 1950);
DISPLAY INVISIBLE (-8975 1950);
FORCEADD UNIVERSAL_GND..1
(-9000 4600);
FORCEPROP 3 LASTPIN (-9000 4650) SIG_NAME T1_GND\g
J 0
(-8990 4660);
DISPLAY 0.659574 (-8990 4660);
PAINT MONO (-8990 4660);
DISPLAY INVISIBLE (-8990 4660);
FORCEPROP 1 LAST HDL_POWER T1_GND
J 1
(-8975 4525);
DISPLAY 0.872340 (-8975 4525);
PAINT GREEN (-8975 4525);
FORCEPROP 2 LAST CDS_LIB pure_quanta_power
J 0
(-9000 4600);
DISPLAY INVISIBLE (-9000 4600);
FORCEPROP 1 LAST PATH I10
J 0
(-8925 4600);
DISPLAY 0.872340 (-8925 4600);
PAINT AQUA (-8925 4600);
DISPLAY INVISIBLE (-8925 4600);
FORCEADD UNIVERSAL_GND..1
(-9000 5125);
FORCEPROP 3 LASTPIN (-9000 5175) SIG_NAME T1_GND\g
J 0
(-8990 5185);
DISPLAY 0.659574 (-8990 5185);
PAINT MONO (-8990 5185);
DISPLAY INVISIBLE (-8990 5185);
FORCEPROP 1 LAST HDL_POWER T1_GND
J 1
(-8975 5050);
DISPLAY 0.872340 (-8975 5050);
PAINT GREEN (-8975 5050);
FORCEPROP 2 LAST CDS_LIB pure_quanta_power
J 0
(-9000 5125);
DISPLAY INVISIBLE (-9000 5125);
FORCEPROP 1 LAST PATH I11
J 0
(-8925 5125);
DISPLAY 0.872340 (-8925 5125);
PAINT AQUA (-8925 5125);
DISPLAY INVISIBLE (-8925 5125);
FORCEADD TDR_3P..2
(-8650 4300);
FORCEPROP 1 LAST LOCATION DB4
J 2
(-8625 4500);
DISPLAY 0.872340 (-8625 4500);
PAINT PINK (-8625 4500);
FORCEPROP 0 LAST $SEC 1
J 0
(-8625 4550);
DISPLAY 0.680851 (-8625 4550);
PAINT MONO (-8625 4550);
DISPLAY INVISIBLE (-8625 4550);
FORCEPROP 0 LAST CDS_SEC 1
J 0
(-8625 4550);
DISPLAY 1.021277 (-8625 4550);
DISPLAY INVISIBLE (-8625 4550);
FORCEPROP 0 LASTPIN (-8850 4300) $PN 1
J 2
(-8860 4310);
DISPLAY 0.680851 (-8860 4310);
PAINT MONO (-8860 4310);
FORCEPROP 0 LASTPIN (-8550 4350) $PN 2
J 0
(-8540 4360);
DISPLAY 0.680851 (-8540 4360);
PAINT MONO (-8540 4360);
FORCEPROP 0 LASTPIN (-8550 4250) $PN 3
J 0
(-8540 4260);
DISPLAY 0.680851 (-8540 4260);
PAINT MONO (-8540 4260);
FORCEPROP 1 LAST PACK_TYPE TH2
J 2
(-8625 4450);
DISPLAY 0.872340 (-8625 4450);
FORCEPROP 1 LAST CDS_LMAN_SYM_OUTLINE -150,100,50,-100
J 0
(-8650 4300);
DISPLAY 0.468085 (-8650 4300);
PAINT GREEN (-8650 4300);
DISPLAY INVISIBLE (-8650 4300);
FORCEPROP 2 LAST CDS_LIB pure_quanta
J 0
(-8650 4300);
DISPLAY INVISIBLE (-8650 4300);
FORCEPROP 1 LAST MATERIAL EMPTY
J 2
(-8650 4450);
DISPLAY 0.872340 (-8650 4450);
PAINT PINK (-8650 4450);
DISPLAY INVISIBLE (-8650 4450);
FORCEPROP 1 LAST PATH I12
J 2
(-8350 4450);
DISPLAY 0.872340 (-8350 4450);
PAINT PINK (-8350 4450);
DISPLAY INVISIBLE (-8350 4450);
FORCEPROP 1 LAST PART_NUMBER N_A
J 1
(-8590 4150);
DISPLAY 0.872340 (-8590 4150);
PAINT PINK (-8590 4150);
DISPLAY INVISIBLE (-8590 4150);
FORCEADD TDR_3P..2
(-8650 4825);
FORCEPROP 1 LAST LOCATION DB3
J 2
(-8625 5025);
DISPLAY 0.872340 (-8625 5025);
PAINT PINK (-8625 5025);
FORCEPROP 0 LAST $SEC 1
J 0
(-8625 5075);
DISPLAY 0.680851 (-8625 5075);
PAINT MONO (-8625 5075);
DISPLAY INVISIBLE (-8625 5075);
FORCEPROP 0 LAST CDS_SEC 1
J 0
(-8625 5075);
DISPLAY 1.021277 (-8625 5075);
DISPLAY INVISIBLE (-8625 5075);
FORCEPROP 0 LASTPIN (-8850 4825) $PN 1
J 2
(-8860 4835);
DISPLAY 0.680851 (-8860 4835);
PAINT MONO (-8860 4835);
FORCEPROP 0 LASTPIN (-8550 4875) $PN 2
J 0
(-8540 4885);
DISPLAY 0.680851 (-8540 4885);
PAINT MONO (-8540 4885);
FORCEPROP 0 LASTPIN (-8550 4775) $PN 3
J 0
(-8540 4785);
DISPLAY 0.680851 (-8540 4785);
PAINT MONO (-8540 4785);
FORCEPROP 1 LAST PACK_TYPE TH2
J 2
(-8625 4975);
DISPLAY 0.872340 (-8625 4975);
FORCEPROP 1 LAST CDS_LMAN_SYM_OUTLINE -150,100,50,-100
J 0
(-8650 4825);
DISPLAY 0.468085 (-8650 4825);
PAINT GREEN (-8650 4825);
DISPLAY INVISIBLE (-8650 4825);
FORCEPROP 2 LAST CDS_LIB pure_quanta
J 0
(-8650 4825);
DISPLAY INVISIBLE (-8650 4825);
FORCEPROP 1 LAST MATERIAL EMPTY
J 2
(-8650 4975);
DISPLAY 0.872340 (-8650 4975);
PAINT PINK (-8650 4975);
DISPLAY INVISIBLE (-8650 4975);
FORCEPROP 1 LAST PATH I13
J 2
(-8350 4975);
DISPLAY 0.872340 (-8350 4975);
PAINT PINK (-8350 4975);
DISPLAY INVISIBLE (-8350 4975);
FORCEPROP 1 LAST PART_NUMBER N_A
J 1
(-8590 4675);
DISPLAY 0.872340 (-8590 4675);
PAINT PINK (-8590 4675);
DISPLAY INVISIBLE (-8590 4675);
FORCEADD UNIVERSAL_GND..1
(-9000 5650);
FORCEPROP 3 LASTPIN (-9000 5700) SIG_NAME T1_GND\g
J 0
(-8990 5710);
DISPLAY 0.659574 (-8990 5710);
PAINT MONO (-8990 5710);
DISPLAY INVISIBLE (-8990 5710);
FORCEPROP 1 LAST HDL_POWER T1_GND
J 1
(-8975 5575);
DISPLAY 0.872340 (-8975 5575);
PAINT GREEN (-8975 5575);
FORCEPROP 2 LAST CDS_LIB pure_quanta_power
J 0
(-9000 5650);
DISPLAY INVISIBLE (-9000 5650);
FORCEPROP 1 LAST PATH I14
J 0
(-8925 5650);
DISPLAY 0.872340 (-8925 5650);
PAINT AQUA (-8925 5650);
DISPLAY INVISIBLE (-8925 5650);
FORCEADD TDR_3P..2
(-8650 5350);
FORCEPROP 1 LAST LOCATION DB2
J 2
(-8625 5550);
DISPLAY 0.872340 (-8625 5550);
PAINT PINK (-8625 5550);
FORCEPROP 0 LAST $SEC 1
J 0
(-8625 5600);
DISPLAY 0.680851 (-8625 5600);
PAINT MONO (-8625 5600);
DISPLAY INVISIBLE (-8625 5600);
FORCEPROP 0 LAST CDS_SEC 1
J 0
(-8625 5600);
DISPLAY 1.021277 (-8625 5600);
DISPLAY INVISIBLE (-8625 5600);
FORCEPROP 0 LASTPIN (-8850 5350) $PN 1
J 2
(-8860 5360);
DISPLAY 0.680851 (-8860 5360);
PAINT MONO (-8860 5360);
FORCEPROP 0 LASTPIN (-8550 5400) $PN 2
J 0
(-8540 5410);
DISPLAY 0.680851 (-8540 5410);
PAINT MONO (-8540 5410);
FORCEPROP 0 LASTPIN (-8550 5300) $PN 3
J 0
(-8540 5310);
DISPLAY 0.680851 (-8540 5310);
PAINT MONO (-8540 5310);
FORCEPROP 1 LAST PACK_TYPE TH2
J 2
(-8625 5500);
DISPLAY 0.872340 (-8625 5500);
FORCEPROP 1 LAST CDS_LMAN_SYM_OUTLINE -150,100,50,-100
J 0
(-8650 5350);
DISPLAY 0.468085 (-8650 5350);
PAINT GREEN (-8650 5350);
DISPLAY INVISIBLE (-8650 5350);
FORCEPROP 2 LAST CDS_LIB pure_quanta
J 0
(-8650 5350);
DISPLAY INVISIBLE (-8650 5350);
FORCEPROP 1 LAST MATERIAL EMPTY
J 2
(-8650 5500);
DISPLAY 0.872340 (-8650 5500);
PAINT PINK (-8650 5500);
DISPLAY INVISIBLE (-8650 5500);
FORCEPROP 1 LAST PATH I15
J 2
(-8350 5500);
DISPLAY 0.872340 (-8350 5500);
PAINT PINK (-8350 5500);
DISPLAY INVISIBLE (-8350 5500);
FORCEPROP 1 LAST PART_NUMBER N_A
J 1
(-8590 5200);
DISPLAY 0.872340 (-8590 5200);
PAINT PINK (-8590 5200);
DISPLAY INVISIBLE (-8590 5200);
FORCEADD TDR_3P..2
(-8650 5875);
FORCEPROP 1 LAST LOCATION DB1
J 2
(-8625 6075);
DISPLAY 0.872340 (-8625 6075);
PAINT PINK (-8625 6075);
FORCEPROP 0 LAST $SEC 1
J 0
(-8625 6125);
DISPLAY 0.680851 (-8625 6125);
PAINT MONO (-8625 6125);
DISPLAY INVISIBLE (-8625 6125);
FORCEPROP 0 LAST CDS_SEC 1
J 0
(-8625 6125);
DISPLAY 1.021277 (-8625 6125);
DISPLAY INVISIBLE (-8625 6125);
FORCEPROP 0 LASTPIN (-8850 5875) $PN 1
J 2
(-8860 5885);
DISPLAY 0.680851 (-8860 5885);
PAINT MONO (-8860 5885);
FORCEPROP 0 LASTPIN (-8550 5925) $PN 2
J 0
(-8540 5935);
DISPLAY 0.680851 (-8540 5935);
PAINT MONO (-8540 5935);
FORCEPROP 0 LASTPIN (-8550 5825) $PN 3
J 0
(-8540 5835);
DISPLAY 0.680851 (-8540 5835);
PAINT MONO (-8540 5835);
FORCEPROP 1 LAST PACK_TYPE TH2
J 2
(-8625 6025);
DISPLAY 0.872340 (-8625 6025);
FORCEPROP 1 LAST MATERIAL EMPTY
J 2
(-8650 6025);
DISPLAY 0.872340 (-8650 6025);
PAINT PINK (-8650 6025);
DISPLAY INVISIBLE (-8650 6025);
FORCEPROP 2 LAST CDS_LIB pure_quanta
J 0
(-8650 5875);
DISPLAY INVISIBLE (-8650 5875);
FORCEPROP 1 LAST CDS_LMAN_SYM_OUTLINE -150,100,50,-100
J 0
(-8650 5875);
DISPLAY 0.468085 (-8650 5875);
PAINT GREEN (-8650 5875);
DISPLAY INVISIBLE (-8650 5875);
FORCEPROP 1 LAST PATH I16
J 2
(-8350 6025);
DISPLAY 0.872340 (-8350 6025);
PAINT PINK (-8350 6025);
DISPLAY INVISIBLE (-8350 6025);
FORCEPROP 1 LAST PART_NUMBER N_A
J 1
(-8590 5725);
DISPLAY 0.872340 (-8590 5725);
PAINT PINK (-8590 5725);
DISPLAY INVISIBLE (-8590 5725);
FORCEADD UNIVERSAL_GND..1
(-7350 1950);
FORCEPROP 3 LASTPIN (-7350 2000) SIG_NAME T1_GND\g
J 0
(-7340 2010);
DISPLAY 0.659574 (-7340 2010);
PAINT MONO (-7340 2010);
DISPLAY INVISIBLE (-7340 2010);
FORCEPROP 1 LAST HDL_POWER T1_GND
J 1
(-7325 1875);
DISPLAY 0.872340 (-7325 1875);
PAINT GREEN (-7325 1875);
FORCEPROP 2 LAST CDS_LIB pure_quanta_power
J 0
(-7350 1950);
DISPLAY INVISIBLE (-7350 1950);
FORCEPROP 1 LAST PATH I17
J 0
(-7275 1950);
DISPLAY 0.872340 (-7275 1950);
PAINT AQUA (-7275 1950);
DISPLAY INVISIBLE (-7275 1950);
FORCEADD TDR_3P..2
(-7000 2175);
FORCEPROP 1 LAST LOCATION DB12
J 2
(-6975 2375);
DISPLAY 0.872340 (-6975 2375);
PAINT PINK (-6975 2375);
FORCEPROP 0 LAST $SEC 1
J 0
(-6975 2425);
DISPLAY 0.680851 (-6975 2425);
PAINT MONO (-6975 2425);
DISPLAY INVISIBLE (-6975 2425);
FORCEPROP 0 LAST CDS_SEC 1
J 0
(-6975 2425);
DISPLAY 1.021277 (-6975 2425);
DISPLAY INVISIBLE (-6975 2425);
FORCEPROP 0 LASTPIN (-7200 2175) $PN 1
J 2
(-7210 2185);
DISPLAY 0.680851 (-7210 2185);
PAINT MONO (-7210 2185);
FORCEPROP 0 LASTPIN (-6900 2225) $PN 2
J 0
(-6890 2235);
DISPLAY 0.680851 (-6890 2235);
PAINT MONO (-6890 2235);
FORCEPROP 0 LASTPIN (-6900 2125) $PN 3
J 0
(-6890 2135);
DISPLAY 0.680851 (-6890 2135);
PAINT MONO (-6890 2135);
FORCEPROP 1 LAST PACK_TYPE TH2
J 2
(-6975 2325);
DISPLAY 0.872340 (-6975 2325);
FORCEPROP 1 LAST CDS_LMAN_SYM_OUTLINE -150,100,50,-100
J 0
(-7000 2175);
DISPLAY 0.468085 (-7000 2175);
PAINT GREEN (-7000 2175);
DISPLAY INVISIBLE (-7000 2175);
FORCEPROP 2 LAST CDS_LIB pure_quanta
J 0
(-7000 2175);
DISPLAY INVISIBLE (-7000 2175);
FORCEPROP 1 LAST MATERIAL EMPTY
J 2
(-7000 2325);
DISPLAY 0.872340 (-7000 2325);
PAINT PINK (-7000 2325);
DISPLAY INVISIBLE (-7000 2325);
FORCEPROP 1 LAST PATH I18
J 2
(-6700 2325);
DISPLAY 0.872340 (-6700 2325);
PAINT PINK (-6700 2325);
DISPLAY INVISIBLE (-6700 2325);
FORCEPROP 1 LAST PART_NUMBER N_A
J 1
(-6940 2025);
DISPLAY 0.872340 (-6940 2025);
PAINT PINK (-6940 2025);
DISPLAY INVISIBLE (-6940 2025);
FORCEADD UNIVERSAL_GND..1
(-7325 2500);
FORCEPROP 3 LASTPIN (-7325 2550) SIG_NAME T1_GND\g
J 0
(-7315 2560);
DISPLAY 0.659574 (-7315 2560);
PAINT MONO (-7315 2560);
DISPLAY INVISIBLE (-7315 2560);
FORCEPROP 1 LAST HDL_POWER T1_GND
J 1
(-7300 2425);
DISPLAY 0.872340 (-7300 2425);
PAINT GREEN (-7300 2425);
FORCEPROP 2 LAST CDS_LIB pure_quanta_power
J 0
(-7325 2500);
DISPLAY INVISIBLE (-7325 2500);
FORCEPROP 1 LAST PATH I19
J 0
(-7250 2500);
DISPLAY 0.872340 (-7250 2500);
PAINT AQUA (-7250 2500);
DISPLAY INVISIBLE (-7250 2500);
FORCEADD TDR_3P..2
(-8700 2175);
FORCEPROP 1 LAST LOCATION DB6
J 2
(-8675 2375);
DISPLAY 0.872340 (-8675 2375);
PAINT PINK (-8675 2375);
FORCEPROP 0 LAST $SEC 1
J 0
(-8675 2425);
DISPLAY 0.680851 (-8675 2425);
PAINT MONO (-8675 2425);
DISPLAY INVISIBLE (-8675 2425);
FORCEPROP 0 LAST CDS_SEC 1
J 0
(-8675 2425);
DISPLAY 1.021277 (-8675 2425);
DISPLAY INVISIBLE (-8675 2425);
FORCEPROP 0 LASTPIN (-8900 2175) $PN 1
J 2
(-8910 2185);
DISPLAY 0.680851 (-8910 2185);
PAINT MONO (-8910 2185);
FORCEPROP 0 LASTPIN (-8600 2225) $PN 2
J 0
(-8590 2235);
DISPLAY 0.680851 (-8590 2235);
PAINT MONO (-8590 2235);
FORCEPROP 0 LASTPIN (-8600 2125) $PN 3
J 0
(-8590 2135);
DISPLAY 0.680851 (-8590 2135);
PAINT MONO (-8590 2135);
FORCEPROP 1 LAST PACK_TYPE TH2
J 2
(-8675 2325);
DISPLAY 0.872340 (-8675 2325);
FORCEPROP 1 LAST MATERIAL EMPTY
J 2
(-8700 2325);
DISPLAY 0.872340 (-8700 2325);
PAINT PINK (-8700 2325);
DISPLAY INVISIBLE (-8700 2325);
FORCEPROP 2 LAST CDS_LIB pure_quanta
J 0
(-8700 2175);
DISPLAY INVISIBLE (-8700 2175);
FORCEPROP 1 LAST CDS_LMAN_SYM_OUTLINE -150,100,50,-100
J 0
(-8700 2175);
DISPLAY 0.468085 (-8700 2175);
PAINT GREEN (-8700 2175);
DISPLAY INVISIBLE (-8700 2175);
FORCEPROP 1 LAST PATH I2
J 2
(-8400 2325);
DISPLAY 0.872340 (-8400 2325);
PAINT PINK (-8400 2325);
DISPLAY INVISIBLE (-8400 2325);
FORCEPROP 1 LAST PART_NUMBER N_A
J 1
(-8640 2025);
DISPLAY 0.872340 (-8640 2025);
PAINT PINK (-8640 2025);
DISPLAY INVISIBLE (-8640 2025);
FORCEADD TDR_3P..2
(-6975 2725);
FORCEPROP 1 LAST LOCATION DB16
J 2
(-6950 2925);
DISPLAY 0.872340 (-6950 2925);
PAINT PINK (-6950 2925);
FORCEPROP 0 LAST $SEC 1
J 0
(-6950 2975);
DISPLAY 0.680851 (-6950 2975);
PAINT MONO (-6950 2975);
DISPLAY INVISIBLE (-6950 2975);
FORCEPROP 0 LAST CDS_SEC 1
J 0
(-6950 2975);
DISPLAY 1.021277 (-6950 2975);
DISPLAY INVISIBLE (-6950 2975);
FORCEPROP 0 LASTPIN (-7175 2725) $PN 1
J 2
(-7185 2735);
DISPLAY 0.680851 (-7185 2735);
PAINT MONO (-7185 2735);
FORCEPROP 0 LASTPIN (-6875 2775) $PN 2
J 0
(-6865 2785);
DISPLAY 0.680851 (-6865 2785);
PAINT MONO (-6865 2785);
FORCEPROP 0 LASTPIN (-6875 2675) $PN 3
J 0
(-6865 2685);
DISPLAY 0.680851 (-6865 2685);
PAINT MONO (-6865 2685);
FORCEPROP 1 LAST PACK_TYPE TH2
J 2
(-6950 2875);
DISPLAY 0.872340 (-6950 2875);
FORCEPROP 1 LAST CDS_LMAN_SYM_OUTLINE -150,100,50,-100
J 0
(-6975 2725);
DISPLAY 0.468085 (-6975 2725);
PAINT GREEN (-6975 2725);
DISPLAY INVISIBLE (-6975 2725);
FORCEPROP 2 LAST CDS_LIB pure_quanta
J 0
(-6975 2725);
DISPLAY INVISIBLE (-6975 2725);
FORCEPROP 1 LAST MATERIAL EMPTY
J 2
(-6975 2875);
DISPLAY 0.872340 (-6975 2875);
PAINT PINK (-6975 2875);
DISPLAY INVISIBLE (-6975 2875);
FORCEPROP 1 LAST PATH I20
J 2
(-6675 2875);
DISPLAY 0.872340 (-6675 2875);
PAINT PINK (-6675 2875);
DISPLAY INVISIBLE (-6675 2875);
FORCEPROP 1 LAST PART_NUMBER N_A
J 1
(-6915 2575);
DISPLAY 0.872340 (-6915 2575);
PAINT PINK (-6915 2575);
DISPLAY INVISIBLE (-6915 2575);
FORCEADD UNIVERSAL_GND..1
(-7325 3025);
FORCEPROP 3 LASTPIN (-7325 3075) SIG_NAME T1_GND\g
J 0
(-7315 3085);
DISPLAY 0.659574 (-7315 3085);
PAINT MONO (-7315 3085);
DISPLAY INVISIBLE (-7315 3085);
FORCEPROP 1 LAST HDL_POWER T1_GND
J 1
(-7300 2950);
DISPLAY 0.872340 (-7300 2950);
PAINT GREEN (-7300 2950);
FORCEPROP 2 LAST CDS_LIB pure_quanta_power
J 0
(-7325 3025);
DISPLAY INVISIBLE (-7325 3025);
FORCEPROP 1 LAST PATH I21
J 0
(-7250 3025);
DISPLAY 0.872340 (-7250 3025);
PAINT AQUA (-7250 3025);
DISPLAY INVISIBLE (-7250 3025);
FORCEADD TDR_3P..2
(-6975 3250);
FORCEPROP 1 LAST LOCATION DB15
J 2
(-6950 3450);
DISPLAY 0.872340 (-6950 3450);
PAINT PINK (-6950 3450);
FORCEPROP 0 LAST $SEC 1
J 0
(-6950 3500);
DISPLAY 0.680851 (-6950 3500);
PAINT MONO (-6950 3500);
DISPLAY INVISIBLE (-6950 3500);
FORCEPROP 0 LAST CDS_SEC 1
J 0
(-6950 3500);
DISPLAY 1.021277 (-6950 3500);
DISPLAY INVISIBLE (-6950 3500);
FORCEPROP 0 LASTPIN (-7175 3250) $PN 1
J 2
(-7185 3260);
DISPLAY 0.680851 (-7185 3260);
PAINT MONO (-7185 3260);
FORCEPROP 0 LASTPIN (-6875 3300) $PN 2
J 0
(-6865 3310);
DISPLAY 0.680851 (-6865 3310);
PAINT MONO (-6865 3310);
FORCEPROP 0 LASTPIN (-6875 3200) $PN 3
J 0
(-6865 3210);
DISPLAY 0.680851 (-6865 3210);
PAINT MONO (-6865 3210);
FORCEPROP 1 LAST PACK_TYPE TH2
J 2
(-6950 3400);
DISPLAY 0.872340 (-6950 3400);
FORCEPROP 1 LAST MATERIAL EMPTY
J 2
(-6975 3400);
DISPLAY 0.872340 (-6975 3400);
PAINT PINK (-6975 3400);
DISPLAY INVISIBLE (-6975 3400);
FORCEPROP 2 LAST CDS_LIB pure_quanta
J 0
(-6975 3250);
DISPLAY INVISIBLE (-6975 3250);
FORCEPROP 1 LAST CDS_LMAN_SYM_OUTLINE -150,100,50,-100
J 0
(-6975 3250);
DISPLAY 0.468085 (-6975 3250);
PAINT GREEN (-6975 3250);
DISPLAY INVISIBLE (-6975 3250);
FORCEPROP 1 LAST PATH I22
J 2
(-6675 3400);
DISPLAY 0.872340 (-6675 3400);
PAINT PINK (-6675 3400);
DISPLAY INVISIBLE (-6675 3400);
FORCEPROP 1 LAST PART_NUMBER N_A
J 1
(-6915 3100);
DISPLAY 0.872340 (-6915 3100);
PAINT PINK (-6915 3100);
DISPLAY INVISIBLE (-6915 3100);
FORCEADD UNIVERSAL_GND..1
(-7300 3550);
FORCEPROP 3 LASTPIN (-7300 3600) SIG_NAME T1_GND\g
J 0
(-7290 3610);
DISPLAY 0.659574 (-7290 3610);
PAINT MONO (-7290 3610);
DISPLAY INVISIBLE (-7290 3610);
FORCEPROP 1 LAST HDL_POWER T1_GND
J 1
(-7275 3475);
DISPLAY 0.872340 (-7275 3475);
PAINT GREEN (-7275 3475);
FORCEPROP 2 LAST CDS_LIB pure_quanta_power
J 0
(-7300 3550);
DISPLAY INVISIBLE (-7300 3550);
FORCEPROP 1 LAST PATH I23
J 0
(-7225 3550);
DISPLAY 0.872340 (-7225 3550);
PAINT AQUA (-7225 3550);
DISPLAY INVISIBLE (-7225 3550);
FORCEADD UNIVERSAL_GND..1
(-7300 4075);
FORCEPROP 3 LASTPIN (-7300 4125) SIG_NAME T1_GND\g
J 0
(-7290 4135);
DISPLAY 0.659574 (-7290 4135);
PAINT MONO (-7290 4135);
DISPLAY INVISIBLE (-7290 4135);
FORCEPROP 1 LAST HDL_POWER T1_GND
J 1
(-7275 4000);
DISPLAY 0.872340 (-7275 4000);
PAINT GREEN (-7275 4000);
FORCEPROP 2 LAST CDS_LIB pure_quanta_power
J 0
(-7300 4075);
DISPLAY INVISIBLE (-7300 4075);
FORCEPROP 1 LAST PATH I24
J 0
(-7225 4075);
DISPLAY 0.872340 (-7225 4075);
PAINT AQUA (-7225 4075);
DISPLAY INVISIBLE (-7225 4075);
FORCEADD TDR_3P..2
(-6950 3775);
FORCEPROP 1 LAST LOCATION DB11
J 2
(-6925 3975);
DISPLAY 0.872340 (-6925 3975);
PAINT PINK (-6925 3975);
FORCEPROP 0 LAST $SEC 1
J 0
(-6925 4025);
DISPLAY 0.680851 (-6925 4025);
PAINT MONO (-6925 4025);
DISPLAY INVISIBLE (-6925 4025);
FORCEPROP 0 LAST CDS_SEC 1
J 0
(-6925 4025);
DISPLAY 1.021277 (-6925 4025);
DISPLAY INVISIBLE (-6925 4025);
FORCEPROP 0 LASTPIN (-7150 3775) $PN 1
J 2
(-7160 3785);
DISPLAY 0.680851 (-7160 3785);
PAINT MONO (-7160 3785);
FORCEPROP 0 LASTPIN (-6850 3825) $PN 2
J 0
(-6840 3835);
DISPLAY 0.680851 (-6840 3835);
PAINT MONO (-6840 3835);
FORCEPROP 0 LASTPIN (-6850 3725) $PN 3
J 0
(-6840 3735);
DISPLAY 0.680851 (-6840 3735);
PAINT MONO (-6840 3735);
FORCEPROP 1 LAST PACK_TYPE TH2
J 2
(-6925 3925);
DISPLAY 0.872340 (-6925 3925);
FORCEPROP 1 LAST CDS_LMAN_SYM_OUTLINE -150,100,50,-100
J 0
(-6950 3775);
DISPLAY 0.468085 (-6950 3775);
PAINT GREEN (-6950 3775);
DISPLAY INVISIBLE (-6950 3775);
FORCEPROP 2 LAST CDS_LIB pure_quanta
J 0
(-6950 3775);
DISPLAY INVISIBLE (-6950 3775);
FORCEPROP 1 LAST MATERIAL EMPTY
J 2
(-6950 3925);
DISPLAY 0.872340 (-6950 3925);
PAINT PINK (-6950 3925);
DISPLAY INVISIBLE (-6950 3925);
FORCEPROP 1 LAST PATH I25
J 2
(-6650 3925);
DISPLAY 0.872340 (-6650 3925);
PAINT PINK (-6650 3925);
DISPLAY INVISIBLE (-6650 3925);
FORCEPROP 1 LAST PART_NUMBER N_A
J 1
(-6890 3625);
DISPLAY 0.872340 (-6890 3625);
PAINT PINK (-6890 3625);
DISPLAY INVISIBLE (-6890 3625);
FORCEADD UNIVERSAL_GND..1
(-5450 425);
FORCEPROP 3 LASTPIN (-5450 475) SIG_NAME T1_GND\g
J 0
(-5440 485);
DISPLAY 0.659574 (-5440 485);
PAINT MONO (-5440 485);
DISPLAY INVISIBLE (-5440 485);
FORCEPROP 1 LAST HDL_POWER T1_GND
J 1
(-5425 350);
DISPLAY 0.872340 (-5425 350);
PAINT GREEN (-5425 350);
FORCEPROP 2 LAST CDS_LIB pure_quanta_power
J 0
(-5450 425);
DISPLAY INVISIBLE (-5450 425);
FORCEPROP 1 LAST PATH I26
J 0
(-5375 425);
DISPLAY 0.872340 (-5375 425);
PAINT AQUA (-5375 425);
DISPLAY INVISIBLE (-5375 425);
FORCEADD UNIVERSAL_GND..1
(-5450 1050);
FORCEPROP 3 LASTPIN (-5450 1100) SIG_NAME T1_GND\g
J 0
(-5440 1110);
DISPLAY 0.659574 (-5440 1110);
PAINT MONO (-5440 1110);
DISPLAY INVISIBLE (-5440 1110);
FORCEPROP 1 LAST HDL_POWER T1_GND
J 1
(-5425 975);
DISPLAY 0.872340 (-5425 975);
PAINT GREEN (-5425 975);
FORCEPROP 2 LAST CDS_LIB pure_quanta_power
J 0
(-5450 1050);
DISPLAY INVISIBLE (-5450 1050);
FORCEPROP 1 LAST PATH I27
J 0
(-5375 1050);
DISPLAY 0.872340 (-5375 1050);
PAINT AQUA (-5375 1050);
DISPLAY INVISIBLE (-5375 1050);
FORCEADD UNIVERSAL_GND..1
(-5450 1825);
FORCEPROP 3 LASTPIN (-5450 1875) SIG_NAME T1_GND\g
J 0
(-5440 1885);
DISPLAY 0.659574 (-5440 1885);
PAINT MONO (-5440 1885);
DISPLAY INVISIBLE (-5440 1885);
FORCEPROP 1 LAST HDL_POWER T1_GND
J 1
(-5425 1750);
DISPLAY 0.872340 (-5425 1750);
PAINT GREEN (-5425 1750);
FORCEPROP 2 LAST CDS_LIB pure_quanta_power
J 0
(-5450 1825);
DISPLAY INVISIBLE (-5450 1825);
FORCEPROP 1 LAST PATH I28
J 0
(-5375 1825);
DISPLAY 0.872340 (-5375 1825);
PAINT AQUA (-5375 1825);
DISPLAY INVISIBLE (-5375 1825);
FORCEADD TP_TDR_4P_FTS..1
(-5025 625);
FORCEPROP 1 LAST LOCATION X6
J 0
(-5150 905);
DISPLAY 0.723404 (-5150 905);
PAINT GREEN (-5150 905);
FORCEPROP 0 LAST $SEC 1
J 0
(-5150 1050);
DISPLAY 0.680851 (-5150 1050);
PAINT MONO (-5150 1050);
DISPLAY INVISIBLE (-5150 1050);
FORCEPROP 0 LAST CDS_SEC 1
J 0
(-5150 1050);
DISPLAY 1.021277 (-5150 1050);
DISPLAY INVISIBLE (-5150 1050);
FORCEPROP 0 LASTPIN (-5300 700) $PN 2
J 2
(-5310 710);
DISPLAY 0.680851 (-5310 710);
PAINT MONO (-5310 710);
FORCEPROP 0 LASTPIN (-5300 550) $PN 3
J 2
(-5310 560);
DISPLAY 0.680851 (-5310 560);
PAINT MONO (-5310 560);
FORCEPROP 0 LASTPIN (-4750 700) $PN 1
J 0
(-4740 710);
DISPLAY 0.680851 (-4740 710);
PAINT MONO (-4740 710);
FORCEPROP 0 LASTPIN (-4750 550) $PN 4
J 0
(-4740 560);
DISPLAY 0.680851 (-4740 560);
PAINT MONO (-4740 560);
FORCEPROP 1 LAST MATERIAL EMPTY
J 0
(-5150 810);
DISPLAY 0.723404 (-5150 810);
PAINT GREEN (-5150 810);
FORCEPROP 2 LAST VALUE TP_TDR_4P_DIP
J 0
(-5150 1000);
DISPLAY 1.021277 (-5150 1000);
FORCEPROP 2 LAST PACK_TYPE TH
J 0
(-5150 950);
DISPLAY 1.021277 (-5150 950);
FORCEPROP 2 LAST CDS_LIB pure_quanta
J 0
(-5025 625);
DISPLAY INVISIBLE (-5025 625);
FORCEPROP 1 LAST NEEDS_NO_SIZE TRUE
J 0
(-5025 625);
DISPLAY 0.468085 (-5025 625);
PAINT GREEN (-5025 625);
DISPLAY INVISIBLE (-5025 625);
FORCEPROP 1 LAST PATH I29
J 0
(-4925 805);
DISPLAY 0.723404 (-4925 805);
PAINT GREEN (-4925 805);
DISPLAY INVISIBLE (-4925 805);
FORCEPROP 1 LAST PART_NUMBER TP15
J 0
(-5150 860);
DISPLAY 0.723404 (-5150 860);
PAINT GREEN (-5150 860);
DISPLAY INVISIBLE (-5150 860);
FORCEADD UNIVERSAL_GND..1
(-9025 2500);
FORCEPROP 3 LASTPIN (-9025 2550) SIG_NAME T1_GND\g
J 0
(-9015 2560);
DISPLAY 0.659574 (-9015 2560);
PAINT MONO (-9015 2560);
DISPLAY INVISIBLE (-9015 2560);
FORCEPROP 1 LAST HDL_POWER T1_GND
J 1
(-9000 2425);
DISPLAY 0.872340 (-9000 2425);
PAINT GREEN (-9000 2425);
FORCEPROP 2 LAST CDS_LIB pure_quanta_power
J 0
(-9025 2500);
DISPLAY INVISIBLE (-9025 2500);
FORCEPROP 1 LAST PATH I3
J 0
(-8950 2500);
DISPLAY 0.872340 (-8950 2500);
PAINT AQUA (-8950 2500);
DISPLAY INVISIBLE (-8950 2500);
FORCEADD TP_TDR_4P_FTS..1
(-5025 1275);
FORCEPROP 1 LAST LOCATION X26
J 0
(-5150 1555);
DISPLAY 0.723404 (-5150 1555);
PAINT GREEN (-5150 1555);
FORCEPROP 0 LAST $SEC 1
J 0
(-5150 1700);
DISPLAY 0.680851 (-5150 1700);
PAINT MONO (-5150 1700);
DISPLAY INVISIBLE (-5150 1700);
FORCEPROP 0 LAST CDS_SEC 1
J 0
(-5150 1700);
DISPLAY 1.021277 (-5150 1700);
DISPLAY INVISIBLE (-5150 1700);
FORCEPROP 0 LASTPIN (-5300 1350) $PN 2
J 2
(-5310 1360);
DISPLAY 0.680851 (-5310 1360);
PAINT MONO (-5310 1360);
FORCEPROP 0 LASTPIN (-5300 1200) $PN 3
J 2
(-5310 1210);
DISPLAY 0.680851 (-5310 1210);
PAINT MONO (-5310 1210);
FORCEPROP 0 LASTPIN (-4750 1350) $PN 1
J 0
(-4740 1360);
DISPLAY 0.680851 (-4740 1360);
PAINT MONO (-4740 1360);
FORCEPROP 0 LASTPIN (-4750 1200) $PN 4
J 0
(-4740 1210);
DISPLAY 0.680851 (-4740 1210);
PAINT MONO (-4740 1210);
FORCEPROP 2 LAST VALUE TP_TDR_4P_DIP
J 0
(-5150 1650);
DISPLAY 1.021277 (-5150 1650);
FORCEPROP 2 LAST PACK_TYPE TH
J 0
(-5150 1600);
DISPLAY 1.021277 (-5150 1600);
FORCEPROP 1 LAST MATERIAL EMPTY
J 0
(-5150 1460);
DISPLAY 0.723404 (-5150 1460);
PAINT GREEN (-5150 1460);
FORCEPROP 2 LAST CDS_LIB pure_quanta
J 0
(-5025 1275);
DISPLAY INVISIBLE (-5025 1275);
FORCEPROP 1 LAST NEEDS_NO_SIZE TRUE
J 0
(-5025 1275);
DISPLAY 0.468085 (-5025 1275);
PAINT GREEN (-5025 1275);
DISPLAY INVISIBLE (-5025 1275);
FORCEPROP 1 LAST PATH I30
J 0
(-4925 1455);
DISPLAY 0.723404 (-4925 1455);
PAINT GREEN (-4925 1455);
DISPLAY INVISIBLE (-4925 1455);
FORCEPROP 1 LAST PART_NUMBER TP15
J 0
(-5150 1510);
DISPLAY 0.723404 (-5150 1510);
PAINT GREEN (-5150 1510);
DISPLAY INVISIBLE (-5150 1510);
FORCEADD TP_TDR_4P_FTS..1
(-5025 2050);
FORCEPROP 1 LAST LOCATION X25
J 0
(-5150 2330);
DISPLAY 0.723404 (-5150 2330);
PAINT GREEN (-5150 2330);
FORCEPROP 0 LAST $SEC 1
J 0
(-5150 2475);
DISPLAY 0.680851 (-5150 2475);
PAINT MONO (-5150 2475);
DISPLAY INVISIBLE (-5150 2475);
FORCEPROP 0 LAST CDS_SEC 1
J 0
(-5150 2475);
DISPLAY 1.021277 (-5150 2475);
DISPLAY INVISIBLE (-5150 2475);
FORCEPROP 0 LASTPIN (-5300 2125) $PN 2
J 2
(-5310 2135);
DISPLAY 0.680851 (-5310 2135);
PAINT MONO (-5310 2135);
FORCEPROP 0 LASTPIN (-5300 1975) $PN 3
J 2
(-5310 1985);
DISPLAY 0.680851 (-5310 1985);
PAINT MONO (-5310 1985);
FORCEPROP 0 LASTPIN (-4750 2125) $PN 1
J 0
(-4740 2135);
DISPLAY 0.680851 (-4740 2135);
PAINT MONO (-4740 2135);
FORCEPROP 0 LASTPIN (-4750 1975) $PN 4
J 0
(-4740 1985);
DISPLAY 0.680851 (-4740 1985);
PAINT MONO (-4740 1985);
FORCEPROP 1 LAST MATERIAL EMPTY
J 0
(-5150 2235);
DISPLAY 0.723404 (-5150 2235);
PAINT GREEN (-5150 2235);
FORCEPROP 2 LAST PACK_TYPE TH
J 0
(-5150 2375);
DISPLAY 1.021277 (-5150 2375);
FORCEPROP 2 LAST VALUE TP_TDR_4P_DIP
J 0
(-5150 2425);
DISPLAY 1.021277 (-5150 2425);
FORCEPROP 2 LAST CDS_LIB pure_quanta
J 0
(-5025 2050);
DISPLAY INVISIBLE (-5025 2050);
FORCEPROP 1 LAST NEEDS_NO_SIZE TRUE
J 0
(-5025 2050);
DISPLAY 0.468085 (-5025 2050);
PAINT GREEN (-5025 2050);
DISPLAY INVISIBLE (-5025 2050);
FORCEPROP 1 LAST PATH I31
J 0
(-4925 2230);
DISPLAY 0.723404 (-4925 2230);
PAINT GREEN (-4925 2230);
DISPLAY INVISIBLE (-4925 2230);
FORCEPROP 1 LAST PART_NUMBER TP15
J 0
(-5150 2285);
DISPLAY 0.723404 (-5150 2285);
PAINT GREEN (-5150 2285);
DISPLAY INVISIBLE (-5150 2285);
FORCEADD UNIVERSAL_GND..1
(-5450 2500);
FORCEPROP 3 LASTPIN (-5450 2550) SIG_NAME T1_GND\g
J 0
(-5440 2560);
DISPLAY 0.659574 (-5440 2560);
PAINT MONO (-5440 2560);
DISPLAY INVISIBLE (-5440 2560);
FORCEPROP 1 LAST HDL_POWER T1_GND
J 1
(-5425 2425);
DISPLAY 0.872340 (-5425 2425);
PAINT GREEN (-5425 2425);
FORCEPROP 2 LAST CDS_LIB pure_quanta_power
J 0
(-5450 2500);
DISPLAY INVISIBLE (-5450 2500);
FORCEPROP 1 LAST PATH I32
J 0
(-5375 2500);
DISPLAY 0.872340 (-5375 2500);
PAINT AQUA (-5375 2500);
DISPLAY INVISIBLE (-5375 2500);
FORCEADD UNIVERSAL_GND..1
(-5450 3275);
FORCEPROP 3 LASTPIN (-5450 3325) SIG_NAME T1_GND\g
J 0
(-5440 3335);
DISPLAY 0.659574 (-5440 3335);
PAINT MONO (-5440 3335);
DISPLAY INVISIBLE (-5440 3335);
FORCEPROP 1 LAST HDL_POWER T1_GND
J 1
(-5425 3200);
DISPLAY 0.872340 (-5425 3200);
PAINT GREEN (-5425 3200);
FORCEPROP 2 LAST CDS_LIB pure_quanta_power
J 0
(-5450 3275);
DISPLAY INVISIBLE (-5450 3275);
FORCEPROP 1 LAST PATH I33
J 0
(-5375 3275);
DISPLAY 0.872340 (-5375 3275);
PAINT AQUA (-5375 3275);
DISPLAY INVISIBLE (-5375 3275);
FORCEADD UNIVERSAL_GND..1
(-5450 4050);
FORCEPROP 3 LASTPIN (-5450 4100) SIG_NAME T1_GND\g
J 0
(-5440 4110);
DISPLAY 0.659574 (-5440 4110);
PAINT MONO (-5440 4110);
DISPLAY INVISIBLE (-5440 4110);
FORCEPROP 1 LAST HDL_POWER T1_GND
J 1
(-5425 3975);
DISPLAY 0.872340 (-5425 3975);
PAINT GREEN (-5425 3975);
FORCEPROP 2 LAST CDS_LIB pure_quanta_power
J 0
(-5450 4050);
DISPLAY INVISIBLE (-5450 4050);
FORCEPROP 1 LAST PATH I34
J 0
(-5375 4050);
DISPLAY 0.872340 (-5375 4050);
PAINT AQUA (-5375 4050);
DISPLAY INVISIBLE (-5375 4050);
FORCEADD TP_TDR_4P_FTS..1
(-5025 2725);
FORCEPROP 1 LAST LOCATION X5
J 0
(-5150 3005);
DISPLAY 0.723404 (-5150 3005);
PAINT GREEN (-5150 3005);
FORCEPROP 0 LAST $SEC 1
J 0
(-5150 3150);
DISPLAY 0.680851 (-5150 3150);
PAINT MONO (-5150 3150);
DISPLAY INVISIBLE (-5150 3150);
FORCEPROP 0 LAST CDS_SEC 1
J 0
(-5150 3150);
DISPLAY 1.021277 (-5150 3150);
DISPLAY INVISIBLE (-5150 3150);
FORCEPROP 0 LASTPIN (-5300 2800) $PN 2
J 2
(-5310 2810);
DISPLAY 0.680851 (-5310 2810);
PAINT MONO (-5310 2810);
FORCEPROP 0 LASTPIN (-5300 2650) $PN 3
J 2
(-5310 2660);
DISPLAY 0.680851 (-5310 2660);
PAINT MONO (-5310 2660);
FORCEPROP 0 LASTPIN (-4750 2800) $PN 1
J 0
(-4740 2810);
DISPLAY 0.680851 (-4740 2810);
PAINT MONO (-4740 2810);
FORCEPROP 0 LASTPIN (-4750 2650) $PN 4
J 0
(-4740 2660);
DISPLAY 0.680851 (-4740 2660);
PAINT MONO (-4740 2660);
FORCEPROP 2 LAST PACK_TYPE TH
J 0
(-5150 3050);
DISPLAY 1.021277 (-5150 3050);
FORCEPROP 1 LAST MATERIAL EMPTY
J 0
(-5150 2910);
DISPLAY 0.723404 (-5150 2910);
PAINT GREEN (-5150 2910);
FORCEPROP 2 LAST VALUE TP_TDR_4P_DIP
J 0
(-5150 3100);
DISPLAY 1.021277 (-5150 3100);
FORCEPROP 2 LAST CDS_LIB pure_quanta
J 0
(-5025 2725);
DISPLAY INVISIBLE (-5025 2725);
FORCEPROP 1 LAST NEEDS_NO_SIZE TRUE
J 0
(-5025 2725);
DISPLAY 0.468085 (-5025 2725);
PAINT GREEN (-5025 2725);
DISPLAY INVISIBLE (-5025 2725);
FORCEPROP 1 LAST PATH I35
J 0
(-4925 2905);
DISPLAY 0.723404 (-4925 2905);
PAINT GREEN (-4925 2905);
DISPLAY INVISIBLE (-4925 2905);
FORCEPROP 1 LAST PART_NUMBER TP15
J 0
(-5150 2960);
DISPLAY 0.723404 (-5150 2960);
PAINT GREEN (-5150 2960);
DISPLAY INVISIBLE (-5150 2960);
FORCEADD TP_TDR_4P_FTS..1
(-5025 3500);
FORCEPROP 1 LAST LOCATION X4
J 0
(-5150 3780);
DISPLAY 0.723404 (-5150 3780);
PAINT GREEN (-5150 3780);
FORCEPROP 0 LAST $SEC 1
J 0
(-5150 3925);
DISPLAY 0.680851 (-5150 3925);
PAINT MONO (-5150 3925);
DISPLAY INVISIBLE (-5150 3925);
FORCEPROP 0 LAST CDS_SEC 1
J 0
(-5150 3925);
DISPLAY 1.021277 (-5150 3925);
DISPLAY INVISIBLE (-5150 3925);
FORCEPROP 0 LASTPIN (-5300 3575) $PN 2
J 2
(-5310 3585);
DISPLAY 0.680851 (-5310 3585);
PAINT MONO (-5310 3585);
FORCEPROP 0 LASTPIN (-5300 3425) $PN 3
J 2
(-5310 3435);
DISPLAY 0.680851 (-5310 3435);
PAINT MONO (-5310 3435);
FORCEPROP 0 LASTPIN (-4750 3575) $PN 1
J 0
(-4740 3585);
DISPLAY 0.680851 (-4740 3585);
PAINT MONO (-4740 3585);
FORCEPROP 0 LASTPIN (-4750 3425) $PN 4
J 0
(-4740 3435);
DISPLAY 0.680851 (-4740 3435);
PAINT MONO (-4740 3435);
FORCEPROP 1 LAST MATERIAL EMPTY
J 0
(-5150 3685);
DISPLAY 0.723404 (-5150 3685);
PAINT GREEN (-5150 3685);
FORCEPROP 2 LAST VALUE TP_TDR_4P_DIP
J 0
(-5150 3875);
DISPLAY 1.021277 (-5150 3875);
FORCEPROP 2 LAST PACK_TYPE TH
J 0
(-5150 3825);
DISPLAY 1.021277 (-5150 3825);
FORCEPROP 2 LAST CDS_LIB pure_quanta
J 0
(-5025 3500);
DISPLAY INVISIBLE (-5025 3500);
FORCEPROP 1 LAST NEEDS_NO_SIZE TRUE
J 0
(-5025 3500);
DISPLAY 0.468085 (-5025 3500);
PAINT GREEN (-5025 3500);
DISPLAY INVISIBLE (-5025 3500);
FORCEPROP 1 LAST PATH I36
J 0
(-4925 3680);
DISPLAY 0.723404 (-4925 3680);
PAINT GREEN (-4925 3680);
DISPLAY INVISIBLE (-4925 3680);
FORCEPROP 1 LAST PART_NUMBER TP15
J 0
(-5150 3735);
DISPLAY 0.723404 (-5150 3735);
PAINT GREEN (-5150 3735);
DISPLAY INVISIBLE (-5150 3735);
FORCEADD TP_TDR_4P_FTS..1
(-5025 4275);
FORCEPROP 1 LAST LOCATION X3
J 0
(-5150 4555);
DISPLAY 0.723404 (-5150 4555);
PAINT GREEN (-5150 4555);
FORCEPROP 0 LAST $SEC 1
J 0
(-5150 4700);
DISPLAY 0.680851 (-5150 4700);
PAINT MONO (-5150 4700);
DISPLAY INVISIBLE (-5150 4700);
FORCEPROP 0 LAST CDS_SEC 1
J 0
(-5150 4700);
DISPLAY 1.021277 (-5150 4700);
DISPLAY INVISIBLE (-5150 4700);
FORCEPROP 0 LASTPIN (-5300 4350) $PN 2
J 2
(-5310 4360);
DISPLAY 0.680851 (-5310 4360);
PAINT MONO (-5310 4360);
FORCEPROP 0 LASTPIN (-5300 4200) $PN 3
J 2
(-5310 4210);
DISPLAY 0.680851 (-5310 4210);
PAINT MONO (-5310 4210);
FORCEPROP 0 LASTPIN (-4750 4350) $PN 1
J 0
(-4740 4360);
DISPLAY 0.680851 (-4740 4360);
PAINT MONO (-4740 4360);
FORCEPROP 0 LASTPIN (-4750 4200) $PN 4
J 0
(-4740 4210);
DISPLAY 0.680851 (-4740 4210);
PAINT MONO (-4740 4210);
FORCEPROP 2 LAST VALUE TP_TDR_4P_DIP
J 0
(-5150 4650);
DISPLAY 1.021277 (-5150 4650);
FORCEPROP 1 LAST MATERIAL EMPTY
J 0
(-5150 4460);
DISPLAY 0.723404 (-5150 4460);
PAINT GREEN (-5150 4460);
FORCEPROP 2 LAST PACK_TYPE TH
J 0
(-5150 4600);
DISPLAY 1.021277 (-5150 4600);
FORCEPROP 2 LAST CDS_LIB pure_quanta
J 0
(-5025 4275);
DISPLAY INVISIBLE (-5025 4275);
FORCEPROP 1 LAST NEEDS_NO_SIZE TRUE
J 0
(-5025 4275);
DISPLAY 0.468085 (-5025 4275);
PAINT GREEN (-5025 4275);
DISPLAY INVISIBLE (-5025 4275);
FORCEPROP 1 LAST PATH I37
J 0
(-4925 4455);
DISPLAY 0.723404 (-4925 4455);
PAINT GREEN (-4925 4455);
DISPLAY INVISIBLE (-4925 4455);
FORCEPROP 1 LAST PART_NUMBER TP15
J 0
(-5150 4510);
DISPLAY 0.723404 (-5150 4510);
PAINT GREEN (-5150 4510);
DISPLAY INVISIBLE (-5150 4510);
FORCEADD TDR_3P..2
(-6950 4300);
FORCEPROP 1 LAST LOCATION DB10
J 2
(-6925 4500);
DISPLAY 0.872340 (-6925 4500);
PAINT PINK (-6925 4500);
FORCEPROP 0 LAST $SEC 1
J 0
(-6925 4550);
DISPLAY 0.680851 (-6925 4550);
PAINT MONO (-6925 4550);
DISPLAY INVISIBLE (-6925 4550);
FORCEPROP 0 LAST CDS_SEC 1
J 0
(-6925 4550);
DISPLAY 1.021277 (-6925 4550);
DISPLAY INVISIBLE (-6925 4550);
FORCEPROP 0 LASTPIN (-7150 4300) $PN 1
J 2
(-7160 4310);
DISPLAY 0.680851 (-7160 4310);
PAINT MONO (-7160 4310);
FORCEPROP 0 LASTPIN (-6850 4350) $PN 2
J 0
(-6840 4360);
DISPLAY 0.680851 (-6840 4360);
PAINT MONO (-6840 4360);
FORCEPROP 0 LASTPIN (-6850 4250) $PN 3
J 0
(-6840 4260);
DISPLAY 0.680851 (-6840 4260);
PAINT MONO (-6840 4260);
FORCEPROP 1 LAST PACK_TYPE TH2
J 2
(-6925 4450);
DISPLAY 0.872340 (-6925 4450);
FORCEPROP 1 LAST MATERIAL EMPTY
J 2
(-6950 4450);
DISPLAY 0.872340 (-6950 4450);
PAINT PINK (-6950 4450);
DISPLAY INVISIBLE (-6950 4450);
FORCEPROP 2 LAST CDS_LIB pure_quanta
J 0
(-6950 4300);
DISPLAY INVISIBLE (-6950 4300);
FORCEPROP 1 LAST CDS_LMAN_SYM_OUTLINE -150,100,50,-100
J 0
(-6950 4300);
DISPLAY 0.468085 (-6950 4300);
PAINT GREEN (-6950 4300);
DISPLAY INVISIBLE (-6950 4300);
FORCEPROP 1 LAST PATH I38
J 2
(-6650 4450);
DISPLAY 0.872340 (-6650 4450);
PAINT PINK (-6650 4450);
DISPLAY INVISIBLE (-6650 4450);
FORCEPROP 1 LAST PART_NUMBER N_A
J 1
(-6890 4150);
DISPLAY 0.872340 (-6890 4150);
PAINT PINK (-6890 4150);
DISPLAY INVISIBLE (-6890 4150);
FORCEADD UNIVERSAL_GND..1
(-7300 4600);
FORCEPROP 3 LASTPIN (-7300 4650) SIG_NAME T1_GND\g
J 0
(-7290 4660);
DISPLAY 0.659574 (-7290 4660);
PAINT MONO (-7290 4660);
DISPLAY INVISIBLE (-7290 4660);
FORCEPROP 1 LAST HDL_POWER T1_GND
J 1
(-7275 4525);
DISPLAY 0.872340 (-7275 4525);
PAINT GREEN (-7275 4525);
FORCEPROP 2 LAST CDS_LIB pure_quanta_power
J 0
(-7300 4600);
DISPLAY INVISIBLE (-7300 4600);
FORCEPROP 1 LAST PATH I39
J 0
(-7225 4600);
DISPLAY 0.872340 (-7225 4600);
PAINT AQUA (-7225 4600);
DISPLAY INVISIBLE (-7225 4600);
FORCEADD UNIVERSAL_GND..1
(-9025 3025);
FORCEPROP 3 LASTPIN (-9025 3075) SIG_NAME T1_GND\g
J 0
(-9015 3085);
DISPLAY 0.659574 (-9015 3085);
PAINT MONO (-9015 3085);
DISPLAY INVISIBLE (-9015 3085);
FORCEPROP 1 LAST HDL_POWER T1_GND
J 1
(-9000 2950);
DISPLAY 0.872340 (-9000 2950);
PAINT GREEN (-9000 2950);
FORCEPROP 2 LAST CDS_LIB pure_quanta_power
J 0
(-9025 3025);
DISPLAY INVISIBLE (-9025 3025);
FORCEPROP 1 LAST PATH I4
J 0
(-8950 3025);
DISPLAY 0.872340 (-8950 3025);
PAINT AQUA (-8950 3025);
DISPLAY INVISIBLE (-8950 3025);
FORCEADD TDR_3P..2
(-6950 4825);
FORCEPROP 1 LAST LOCATION DB9
J 2
(-6925 5025);
DISPLAY 0.872340 (-6925 5025);
PAINT PINK (-6925 5025);
FORCEPROP 0 LAST $SEC 1
J 0
(-6925 5075);
DISPLAY 0.680851 (-6925 5075);
PAINT MONO (-6925 5075);
DISPLAY INVISIBLE (-6925 5075);
FORCEPROP 0 LAST CDS_SEC 1
J 0
(-6925 5075);
DISPLAY 1.021277 (-6925 5075);
DISPLAY INVISIBLE (-6925 5075);
FORCEPROP 0 LASTPIN (-7150 4825) $PN 1
J 2
(-7160 4835);
DISPLAY 0.680851 (-7160 4835);
PAINT MONO (-7160 4835);
FORCEPROP 0 LASTPIN (-6850 4875) $PN 2
J 0
(-6840 4885);
DISPLAY 0.680851 (-6840 4885);
PAINT MONO (-6840 4885);
FORCEPROP 0 LASTPIN (-6850 4775) $PN 3
J 0
(-6840 4785);
DISPLAY 0.680851 (-6840 4785);
PAINT MONO (-6840 4785);
FORCEPROP 1 LAST PACK_TYPE TH2
J 2
(-6925 4975);
DISPLAY 0.872340 (-6925 4975);
FORCEPROP 1 LAST MATERIAL EMPTY
J 2
(-6950 4975);
DISPLAY 0.872340 (-6950 4975);
PAINT PINK (-6950 4975);
DISPLAY INVISIBLE (-6950 4975);
FORCEPROP 2 LAST CDS_LIB pure_quanta
J 0
(-6950 4825);
DISPLAY INVISIBLE (-6950 4825);
FORCEPROP 1 LAST CDS_LMAN_SYM_OUTLINE -150,100,50,-100
J 0
(-6950 4825);
DISPLAY 0.468085 (-6950 4825);
PAINT GREEN (-6950 4825);
DISPLAY INVISIBLE (-6950 4825);
FORCEPROP 1 LAST PATH I40
J 2
(-6650 4975);
DISPLAY 0.872340 (-6650 4975);
PAINT PINK (-6650 4975);
DISPLAY INVISIBLE (-6650 4975);
FORCEPROP 1 LAST PART_NUMBER N_A
J 1
(-6890 4675);
DISPLAY 0.872340 (-6890 4675);
PAINT PINK (-6890 4675);
DISPLAY INVISIBLE (-6890 4675);
FORCEADD UNIVERSAL_GND..1
(-7300 5125);
FORCEPROP 3 LASTPIN (-7300 5175) SIG_NAME T1_GND\g
J 0
(-7290 5185);
DISPLAY 0.659574 (-7290 5185);
PAINT MONO (-7290 5185);
DISPLAY INVISIBLE (-7290 5185);
FORCEPROP 1 LAST HDL_POWER T1_GND
J 1
(-7275 5050);
DISPLAY 0.872340 (-7275 5050);
PAINT GREEN (-7275 5050);
FORCEPROP 2 LAST CDS_LIB pure_quanta_power
J 0
(-7300 5125);
DISPLAY INVISIBLE (-7300 5125);
FORCEPROP 1 LAST PATH I41
J 0
(-7225 5125);
DISPLAY 0.872340 (-7225 5125);
PAINT AQUA (-7225 5125);
DISPLAY INVISIBLE (-7225 5125);
FORCEADD TDR_3P..2
(-6950 5350);
FORCEPROP 1 LAST LOCATION DB8
J 2
(-6925 5550);
DISPLAY 0.872340 (-6925 5550);
PAINT PINK (-6925 5550);
FORCEPROP 0 LAST $SEC 1
J 0
(-6925 5600);
DISPLAY 0.680851 (-6925 5600);
PAINT MONO (-6925 5600);
DISPLAY INVISIBLE (-6925 5600);
FORCEPROP 0 LAST CDS_SEC 1
J 0
(-6925 5600);
DISPLAY 1.021277 (-6925 5600);
DISPLAY INVISIBLE (-6925 5600);
FORCEPROP 0 LASTPIN (-7150 5350) $PN 1
J 2
(-7160 5360);
DISPLAY 0.680851 (-7160 5360);
PAINT MONO (-7160 5360);
FORCEPROP 0 LASTPIN (-6850 5400) $PN 2
J 0
(-6840 5410);
DISPLAY 0.680851 (-6840 5410);
PAINT MONO (-6840 5410);
FORCEPROP 0 LASTPIN (-6850 5300) $PN 3
J 0
(-6840 5310);
DISPLAY 0.680851 (-6840 5310);
PAINT MONO (-6840 5310);
FORCEPROP 1 LAST PACK_TYPE TH2
J 2
(-6925 5500);
DISPLAY 0.872340 (-6925 5500);
FORCEPROP 1 LAST MATERIAL EMPTY
J 2
(-6950 5500);
DISPLAY 0.872340 (-6950 5500);
PAINT PINK (-6950 5500);
DISPLAY INVISIBLE (-6950 5500);
FORCEPROP 2 LAST CDS_LIB pure_quanta
J 0
(-6950 5350);
DISPLAY INVISIBLE (-6950 5350);
FORCEPROP 1 LAST CDS_LMAN_SYM_OUTLINE -150,100,50,-100
J 0
(-6950 5350);
DISPLAY 0.468085 (-6950 5350);
PAINT GREEN (-6950 5350);
DISPLAY INVISIBLE (-6950 5350);
FORCEPROP 1 LAST PATH I42
J 2
(-6650 5500);
DISPLAY 0.872340 (-6650 5500);
PAINT PINK (-6650 5500);
DISPLAY INVISIBLE (-6650 5500);
FORCEPROP 1 LAST PART_NUMBER N_A
J 1
(-6890 5200);
DISPLAY 0.872340 (-6890 5200);
PAINT PINK (-6890 5200);
DISPLAY INVISIBLE (-6890 5200);
FORCEADD UNIVERSAL_GND..1
(-7300 5650);
FORCEPROP 3 LASTPIN (-7300 5700) SIG_NAME T1_GND\g
J 0
(-7290 5710);
DISPLAY 0.659574 (-7290 5710);
PAINT MONO (-7290 5710);
DISPLAY INVISIBLE (-7290 5710);
FORCEPROP 1 LAST HDL_POWER T1_GND
J 1
(-7275 5575);
DISPLAY 0.872340 (-7275 5575);
PAINT GREEN (-7275 5575);
FORCEPROP 2 LAST CDS_LIB pure_quanta_power
J 0
(-7300 5650);
DISPLAY INVISIBLE (-7300 5650);
FORCEPROP 1 LAST PATH I43
J 0
(-7225 5650);
DISPLAY 0.872340 (-7225 5650);
PAINT AQUA (-7225 5650);
DISPLAY INVISIBLE (-7225 5650);
FORCEADD TDR_3P..2
(-6950 5875);
FORCEPROP 1 LAST LOCATION DB7
J 2
(-6925 6075);
DISPLAY 0.872340 (-6925 6075);
PAINT PINK (-6925 6075);
FORCEPROP 0 LAST $SEC 1
J 0
(-6925 6125);
DISPLAY 0.680851 (-6925 6125);
PAINT MONO (-6925 6125);
DISPLAY INVISIBLE (-6925 6125);
FORCEPROP 0 LAST CDS_SEC 1
J 0
(-6925 6125);
DISPLAY 1.021277 (-6925 6125);
DISPLAY INVISIBLE (-6925 6125);
FORCEPROP 0 LASTPIN (-7150 5875) $PN 1
J 2
(-7160 5885);
DISPLAY 0.680851 (-7160 5885);
PAINT MONO (-7160 5885);
FORCEPROP 0 LASTPIN (-6850 5925) $PN 2
J 0
(-6840 5935);
DISPLAY 0.680851 (-6840 5935);
PAINT MONO (-6840 5935);
FORCEPROP 0 LASTPIN (-6850 5825) $PN 3
J 0
(-6840 5835);
DISPLAY 0.680851 (-6840 5835);
PAINT MONO (-6840 5835);
FORCEPROP 1 LAST PACK_TYPE TH2
J 2
(-6925 6025);
DISPLAY 0.872340 (-6925 6025);
FORCEPROP 1 LAST CDS_LMAN_SYM_OUTLINE -150,100,50,-100
J 0
(-6950 5875);
DISPLAY 0.468085 (-6950 5875);
PAINT GREEN (-6950 5875);
DISPLAY INVISIBLE (-6950 5875);
FORCEPROP 2 LAST CDS_LIB pure_quanta
J 0
(-6950 5875);
DISPLAY INVISIBLE (-6950 5875);
FORCEPROP 1 LAST MATERIAL EMPTY
J 2
(-6950 6025);
DISPLAY 0.872340 (-6950 6025);
PAINT PINK (-6950 6025);
DISPLAY INVISIBLE (-6950 6025);
FORCEPROP 1 LAST PATH I44
J 2
(-6650 6025);
DISPLAY 0.872340 (-6650 6025);
PAINT PINK (-6650 6025);
DISPLAY INVISIBLE (-6650 6025);
FORCEPROP 1 LAST PART_NUMBER N_A
J 1
(-6890 5725);
DISPLAY 0.872340 (-6890 5725);
PAINT PINK (-6890 5725);
DISPLAY INVISIBLE (-6890 5725);
FORCEADD UNIVERSAL_GND..1
(-5450 4825);
FORCEPROP 3 LASTPIN (-5450 4875) SIG_NAME T1_GND\g
J 0
(-5440 4885);
DISPLAY 0.659574 (-5440 4885);
PAINT MONO (-5440 4885);
DISPLAY INVISIBLE (-5440 4885);
FORCEPROP 1 LAST HDL_POWER T1_GND
J 1
(-5425 4750);
DISPLAY 0.872340 (-5425 4750);
PAINT GREEN (-5425 4750);
FORCEPROP 2 LAST CDS_LIB pure_quanta_power
J 0
(-5450 4825);
DISPLAY INVISIBLE (-5450 4825);
FORCEPROP 1 LAST PATH I45
J 0
(-5375 4825);
DISPLAY 0.872340 (-5375 4825);
PAINT AQUA (-5375 4825);
DISPLAY INVISIBLE (-5375 4825);
FORCEADD UNIVERSAL_GND..1
(-5450 5600);
FORCEPROP 3 LASTPIN (-5450 5650) SIG_NAME T1_GND\g
J 0
(-5440 5660);
DISPLAY 0.659574 (-5440 5660);
PAINT MONO (-5440 5660);
DISPLAY INVISIBLE (-5440 5660);
FORCEPROP 1 LAST HDL_POWER T1_GND
J 1
(-5425 5525);
DISPLAY 0.872340 (-5425 5525);
PAINT GREEN (-5425 5525);
FORCEPROP 2 LAST CDS_LIB pure_quanta_power
J 0
(-5450 5600);
DISPLAY INVISIBLE (-5450 5600);
FORCEPROP 1 LAST PATH I46
J 0
(-5375 5600);
DISPLAY 0.872340 (-5375 5600);
PAINT AQUA (-5375 5600);
DISPLAY INVISIBLE (-5375 5600);
FORCEADD TP_TDR_4P_FTS..1
(-5025 5050);
FORCEPROP 1 LAST LOCATION X2
J 0
(-5150 5330);
DISPLAY 0.723404 (-5150 5330);
PAINT GREEN (-5150 5330);
FORCEPROP 0 LAST $SEC 1
J 0
(-5150 5475);
DISPLAY 0.680851 (-5150 5475);
PAINT MONO (-5150 5475);
DISPLAY INVISIBLE (-5150 5475);
FORCEPROP 0 LAST CDS_SEC 1
J 0
(-5150 5475);
DISPLAY 1.021277 (-5150 5475);
DISPLAY INVISIBLE (-5150 5475);
FORCEPROP 0 LASTPIN (-5300 5125) $PN 2
J 2
(-5310 5135);
DISPLAY 0.680851 (-5310 5135);
PAINT MONO (-5310 5135);
FORCEPROP 0 LASTPIN (-5300 4975) $PN 3
J 2
(-5310 4985);
DISPLAY 0.680851 (-5310 4985);
PAINT MONO (-5310 4985);
FORCEPROP 0 LASTPIN (-4750 5125) $PN 1
J 0
(-4740 5135);
DISPLAY 0.680851 (-4740 5135);
PAINT MONO (-4740 5135);
FORCEPROP 0 LASTPIN (-4750 4975) $PN 4
J 0
(-4740 4985);
DISPLAY 0.680851 (-4740 4985);
PAINT MONO (-4740 4985);
FORCEPROP 1 LAST MATERIAL EMPTY
J 0
(-5150 5235);
DISPLAY 0.723404 (-5150 5235);
PAINT GREEN (-5150 5235);
FORCEPROP 2 LAST PACK_TYPE TH
J 0
(-5150 5375);
DISPLAY 1.021277 (-5150 5375);
FORCEPROP 2 LAST VALUE TP_TDR_4P_DIP
J 0
(-5150 5425);
DISPLAY 1.021277 (-5150 5425);
FORCEPROP 1 LAST NEEDS_NO_SIZE TRUE
J 0
(-5025 5050);
DISPLAY 0.468085 (-5025 5050);
PAINT GREEN (-5025 5050);
DISPLAY INVISIBLE (-5025 5050);
FORCEPROP 2 LAST CDS_LIB pure_quanta
J 0
(-5025 5050);
DISPLAY INVISIBLE (-5025 5050);
FORCEPROP 1 LAST PATH I47
J 0
(-4925 5230);
DISPLAY 0.723404 (-4925 5230);
PAINT GREEN (-4925 5230);
DISPLAY INVISIBLE (-4925 5230);
FORCEPROP 1 LAST PART_NUMBER TP15
J 0
(-5150 5285);
DISPLAY 0.723404 (-5150 5285);
PAINT GREEN (-5150 5285);
DISPLAY INVISIBLE (-5150 5285);
FORCEADD TP_TDR_4P_FTS..1
(-5025 5825);
FORCEPROP 1 LAST LOCATION X1
J 0
(-5150 6105);
DISPLAY 0.723404 (-5150 6105);
PAINT GREEN (-5150 6105);
FORCEPROP 0 LAST $SEC 1
J 0
(-5150 6250);
DISPLAY 0.680851 (-5150 6250);
PAINT MONO (-5150 6250);
DISPLAY INVISIBLE (-5150 6250);
FORCEPROP 0 LAST CDS_SEC 1
J 0
(-5150 6250);
DISPLAY 1.021277 (-5150 6250);
DISPLAY INVISIBLE (-5150 6250);
FORCEPROP 0 LASTPIN (-5300 5900) $PN 2
J 2
(-5310 5910);
DISPLAY 0.680851 (-5310 5910);
PAINT MONO (-5310 5910);
FORCEPROP 0 LASTPIN (-5300 5750) $PN 3
J 2
(-5310 5760);
DISPLAY 0.680851 (-5310 5760);
PAINT MONO (-5310 5760);
FORCEPROP 0 LASTPIN (-4750 5900) $PN 1
J 0
(-4740 5910);
DISPLAY 0.680851 (-4740 5910);
PAINT MONO (-4740 5910);
FORCEPROP 0 LASTPIN (-4750 5750) $PN 4
J 0
(-4740 5760);
DISPLAY 0.680851 (-4740 5760);
PAINT MONO (-4740 5760);
FORCEPROP 1 LAST MATERIAL EMPTY
J 0
(-5150 6010);
DISPLAY 0.723404 (-5150 6010);
PAINT GREEN (-5150 6010);
FORCEPROP 2 LAST PACK_TYPE TH
J 0
(-5150 6150);
DISPLAY 1.021277 (-5150 6150);
FORCEPROP 2 LAST VALUE TP_TDR_4P_DIP
J 0
(-5150 6200);
DISPLAY 1.021277 (-5150 6200);
FORCEPROP 1 LAST NEEDS_NO_SIZE TRUE
J 0
(-5025 5825);
DISPLAY 0.468085 (-5025 5825);
PAINT GREEN (-5025 5825);
DISPLAY INVISIBLE (-5025 5825);
FORCEPROP 2 LAST CDS_LIB pure_quanta
J 0
(-5025 5825);
DISPLAY INVISIBLE (-5025 5825);
FORCEPROP 1 LAST PATH I48
J 0
(-4925 6005);
DISPLAY 0.723404 (-4925 6005);
PAINT GREEN (-4925 6005);
DISPLAY INVISIBLE (-4925 6005);
FORCEPROP 1 LAST PART_NUMBER TP15
J 0
(-5150 6060);
DISPLAY 0.723404 (-5150 6060);
PAINT GREEN (-5150 6060);
DISPLAY INVISIBLE (-5150 6060);
FORCEADD TP_TDR_4P_FTS..1
R 4
(-3700 625);
FORCEPROP 1 LAST LOCATION X12
J 0
(-3825 920);
DISPLAY 0.723404 (-3825 920);
PAINT GREEN (-3825 920);
FORCEPROP 0 LAST $SEC 1
J 0
(-3825 1050);
DISPLAY 0.680851 (-3825 1050);
PAINT MONO (-3825 1050);
DISPLAY INVISIBLE (-3825 1050);
FORCEPROP 0 LAST CDS_SEC 1
J 0
(-3825 1050);
DISPLAY 1.021277 (-3825 1050);
DISPLAY INVISIBLE (-3825 1050);
FORCEPROP 0 LASTPIN (-3425 550) $PN 2
J 0
(-3415 560);
DISPLAY 0.680851 (-3415 560);
PAINT MONO (-3415 560);
FORCEPROP 0 LASTPIN (-3425 700) $PN 3
J 0
(-3415 710);
DISPLAY 0.680851 (-3415 710);
PAINT MONO (-3415 710);
FORCEPROP 0 LASTPIN (-3975 550) $PN 1
J 2
(-3985 560);
DISPLAY 0.680851 (-3985 560);
PAINT MONO (-3985 560);
FORCEPROP 0 LASTPIN (-3975 700) $PN 4
J 2
(-3985 710);
DISPLAY 0.680851 (-3985 710);
PAINT MONO (-3985 710);
FORCEPROP 1 LAST MATERIAL EMPTY
J 0
(-3825 1015);
DISPLAY 0.723404 (-3825 1015);
PAINT GREEN (-3825 1015);
FORCEPROP 2 LAST PACK_TYPE TH
J 0
(-3825 875);
DISPLAY 1.021277 (-3825 875);
FORCEPROP 2 LAST VALUE TP_TDR_4P_DIP
J 0
(-3825 825);
DISPLAY 1.021277 (-3825 825);
FORCEPROP 2 LAST CDS_LIB pure_quanta
R 2
J 0
(-3700 625);
DISPLAY INVISIBLE (-3700 625);
FORCEPROP 1 LAST NEEDS_NO_SIZE TRUE
R 2
J 0
(-3700 625);
DISPLAY 0.468085 (-3700 625);
PAINT GREEN (-3700 625);
DISPLAY INVISIBLE (-3700 625);
FORCEPROP 1 LAST PATH I49
R 2
J 0
(-3800 445);
DISPLAY 0.723404 (-3800 445);
PAINT GREEN (-3800 445);
DISPLAY INVISIBLE (-3800 445);
FORCEPROP 1 LAST PART_NUMBER TP15
J 0
(-3825 965);
DISPLAY 0.723404 (-3825 965);
PAINT GREEN (-3825 965);
DISPLAY INVISIBLE (-3825 965);
FORCEADD TDR_3P..2
(-8675 2725);
FORCEPROP 1 LAST LOCATION DB14
J 2
(-8650 2925);
DISPLAY 0.872340 (-8650 2925);
PAINT PINK (-8650 2925);
FORCEPROP 0 LAST $SEC 1
J 0
(-8650 2975);
DISPLAY 0.680851 (-8650 2975);
PAINT MONO (-8650 2975);
DISPLAY INVISIBLE (-8650 2975);
FORCEPROP 0 LAST CDS_SEC 1
J 0
(-8650 2975);
DISPLAY 1.021277 (-8650 2975);
DISPLAY INVISIBLE (-8650 2975);
FORCEPROP 0 LASTPIN (-8875 2725) $PN 1
J 2
(-8885 2735);
DISPLAY 0.680851 (-8885 2735);
PAINT MONO (-8885 2735);
FORCEPROP 0 LASTPIN (-8575 2775) $PN 2
J 0
(-8565 2785);
DISPLAY 0.680851 (-8565 2785);
PAINT MONO (-8565 2785);
FORCEPROP 0 LASTPIN (-8575 2675) $PN 3
J 0
(-8565 2685);
DISPLAY 0.680851 (-8565 2685);
PAINT MONO (-8565 2685);
FORCEPROP 1 LAST PACK_TYPE TH2
J 2
(-8650 2875);
DISPLAY 0.872340 (-8650 2875);
FORCEPROP 1 LAST MATERIAL EMPTY
J 2
(-8675 2875);
DISPLAY 0.872340 (-8675 2875);
PAINT PINK (-8675 2875);
DISPLAY INVISIBLE (-8675 2875);
FORCEPROP 2 LAST CDS_LIB pure_quanta
J 0
(-8675 2725);
DISPLAY INVISIBLE (-8675 2725);
FORCEPROP 1 LAST CDS_LMAN_SYM_OUTLINE -150,100,50,-100
J 0
(-8675 2725);
DISPLAY 0.468085 (-8675 2725);
PAINT GREEN (-8675 2725);
DISPLAY INVISIBLE (-8675 2725);
FORCEPROP 1 LAST PATH I5
J 2
(-8375 2875);
DISPLAY 0.872340 (-8375 2875);
PAINT PINK (-8375 2875);
DISPLAY INVISIBLE (-8375 2875);
FORCEPROP 1 LAST PART_NUMBER N_A
J 1
(-8615 2575);
DISPLAY 0.872340 (-8615 2575);
PAINT PINK (-8615 2575);
DISPLAY INVISIBLE (-8615 2575);
FORCEADD UNIVERSAL_GND..1
(-3300 425);
FORCEPROP 3 LASTPIN (-3300 475) SIG_NAME T1_GND\g
J 0
(-3290 485);
DISPLAY 0.659574 (-3290 485);
PAINT MONO (-3290 485);
DISPLAY INVISIBLE (-3290 485);
FORCEPROP 1 LAST HDL_POWER T1_GND
J 1
(-3275 350);
DISPLAY 0.872340 (-3275 350);
PAINT GREEN (-3275 350);
FORCEPROP 2 LAST CDS_LIB pure_quanta_power
J 0
(-3300 425);
DISPLAY INVISIBLE (-3300 425);
FORCEPROP 1 LAST PATH I50
J 0
(-3225 425);
DISPLAY 0.872340 (-3225 425);
PAINT AQUA (-3225 425);
DISPLAY INVISIBLE (-3225 425);
FORCEADD UNIVERSAL_GND..1
(-3300 1050);
FORCEPROP 3 LASTPIN (-3300 1100) SIG_NAME T1_GND\g
J 0
(-3290 1110);
DISPLAY 0.659574 (-3290 1110);
PAINT MONO (-3290 1110);
DISPLAY INVISIBLE (-3290 1110);
FORCEPROP 1 LAST HDL_POWER T1_GND
J 1
(-3275 975);
DISPLAY 0.872340 (-3275 975);
PAINT GREEN (-3275 975);
FORCEPROP 2 LAST CDS_LIB pure_quanta_power
J 0
(-3300 1050);
DISPLAY INVISIBLE (-3300 1050);
FORCEPROP 1 LAST PATH I51
J 0
(-3225 1050);
DISPLAY 0.872340 (-3225 1050);
PAINT AQUA (-3225 1050);
DISPLAY INVISIBLE (-3225 1050);
FORCEADD TP_TDR_4P_FTS..1
R 4
(-3700 1275);
FORCEPROP 1 LAST LOCATION X28
J 0
(-3825 1570);
DISPLAY 0.723404 (-3825 1570);
PAINT GREEN (-3825 1570);
FORCEPROP 0 LAST $SEC 1
J 0
(-3825 1700);
DISPLAY 0.680851 (-3825 1700);
PAINT MONO (-3825 1700);
DISPLAY INVISIBLE (-3825 1700);
FORCEPROP 0 LAST CDS_SEC 1
J 0
(-3825 1700);
DISPLAY 1.021277 (-3825 1700);
DISPLAY INVISIBLE (-3825 1700);
FORCEPROP 0 LASTPIN (-3425 1200) $PN 2
J 0
(-3415 1210);
DISPLAY 0.680851 (-3415 1210);
PAINT MONO (-3415 1210);
FORCEPROP 0 LASTPIN (-3425 1350) $PN 3
J 0
(-3415 1360);
DISPLAY 0.680851 (-3415 1360);
PAINT MONO (-3415 1360);
FORCEPROP 0 LASTPIN (-3975 1200) $PN 1
J 2
(-3985 1210);
DISPLAY 0.680851 (-3985 1210);
PAINT MONO (-3985 1210);
FORCEPROP 0 LASTPIN (-3975 1350) $PN 4
J 2
(-3985 1360);
DISPLAY 0.680851 (-3985 1360);
PAINT MONO (-3985 1360);
FORCEPROP 2 LAST PACK_TYPE TH
J 0
(-3825 1525);
DISPLAY 1.021277 (-3825 1525);
FORCEPROP 1 LAST MATERIAL EMPTY
J 0
(-3825 1665);
DISPLAY 0.723404 (-3825 1665);
PAINT GREEN (-3825 1665);
FORCEPROP 2 LAST VALUE TP_TDR_4P_DIP
J 0
(-3825 1475);
DISPLAY 1.021277 (-3825 1475);
FORCEPROP 2 LAST CDS_LIB pure_quanta
R 2
J 0
(-3700 1275);
DISPLAY INVISIBLE (-3700 1275);
FORCEPROP 1 LAST NEEDS_NO_SIZE TRUE
R 2
J 0
(-3700 1275);
DISPLAY 0.468085 (-3700 1275);
PAINT GREEN (-3700 1275);
DISPLAY INVISIBLE (-3700 1275);
FORCEPROP 1 LAST PATH I52
R 2
J 0
(-3800 1095);
DISPLAY 0.723404 (-3800 1095);
PAINT GREEN (-3800 1095);
DISPLAY INVISIBLE (-3800 1095);
FORCEPROP 1 LAST PART_NUMBER TP15
J 0
(-3825 1615);
DISPLAY 0.723404 (-3825 1615);
PAINT GREEN (-3825 1615);
DISPLAY INVISIBLE (-3825 1615);
FORCEADD TP_TDR_4P_FTS..1
R 4
(-3700 2050);
FORCEPROP 1 LAST LOCATION X27
J 0
(-3825 2345);
DISPLAY 0.723404 (-3825 2345);
PAINT GREEN (-3825 2345);
FORCEPROP 0 LAST $SEC 1
J 0
(-3825 2475);
DISPLAY 0.680851 (-3825 2475);
PAINT MONO (-3825 2475);
DISPLAY INVISIBLE (-3825 2475);
FORCEPROP 0 LAST CDS_SEC 1
J 0
(-3825 2475);
DISPLAY 1.021277 (-3825 2475);
DISPLAY INVISIBLE (-3825 2475);
FORCEPROP 0 LASTPIN (-3425 1975) $PN 2
J 0
(-3415 1985);
DISPLAY 0.680851 (-3415 1985);
PAINT MONO (-3415 1985);
FORCEPROP 0 LASTPIN (-3425 2125) $PN 3
J 0
(-3415 2135);
DISPLAY 0.680851 (-3415 2135);
PAINT MONO (-3415 2135);
FORCEPROP 0 LASTPIN (-3975 1975) $PN 1
J 2
(-3985 1985);
DISPLAY 0.680851 (-3985 1985);
PAINT MONO (-3985 1985);
FORCEPROP 0 LASTPIN (-3975 2125) $PN 4
J 2
(-3985 2135);
DISPLAY 0.680851 (-3985 2135);
PAINT MONO (-3985 2135);
FORCEPROP 2 LAST PACK_TYPE TH
J 0
(-3825 2300);
DISPLAY 1.021277 (-3825 2300);
FORCEPROP 2 LAST VALUE TP_TDR_4P_DIP
J 0
(-3825 2250);
DISPLAY 1.021277 (-3825 2250);
FORCEPROP 1 LAST MATERIAL EMPTY
J 0
(-3825 2440);
DISPLAY 0.723404 (-3825 2440);
PAINT GREEN (-3825 2440);
FORCEPROP 2 LAST CDS_LIB pure_quanta
R 2
J 0
(-3700 2050);
DISPLAY INVISIBLE (-3700 2050);
FORCEPROP 1 LAST NEEDS_NO_SIZE TRUE
R 2
J 0
(-3700 2050);
DISPLAY 0.468085 (-3700 2050);
PAINT GREEN (-3700 2050);
DISPLAY INVISIBLE (-3700 2050);
FORCEPROP 1 LAST PATH I53
R 2
J 0
(-3800 1870);
DISPLAY 0.723404 (-3800 1870);
PAINT GREEN (-3800 1870);
DISPLAY INVISIBLE (-3800 1870);
FORCEPROP 1 LAST PART_NUMBER TP15
J 0
(-3825 2390);
DISPLAY 0.723404 (-3825 2390);
PAINT GREEN (-3825 2390);
DISPLAY INVISIBLE (-3825 2390);
FORCEADD UNIVERSAL_GND..1
(-3300 1825);
FORCEPROP 3 LASTPIN (-3300 1875) SIG_NAME T1_GND\g
J 0
(-3290 1885);
DISPLAY 0.659574 (-3290 1885);
PAINT MONO (-3290 1885);
DISPLAY INVISIBLE (-3290 1885);
FORCEPROP 1 LAST HDL_POWER T1_GND
J 1
(-3275 1750);
DISPLAY 0.872340 (-3275 1750);
PAINT GREEN (-3275 1750);
FORCEPROP 2 LAST CDS_LIB pure_quanta_power
J 0
(-3300 1825);
DISPLAY INVISIBLE (-3300 1825);
FORCEPROP 1 LAST PATH I54
J 0
(-3225 1825);
DISPLAY 0.872340 (-3225 1825);
PAINT AQUA (-3225 1825);
DISPLAY INVISIBLE (-3225 1825);
FORCEADD UNIVERSAL_GND..1
(-2625 450);
FORCEPROP 3 LASTPIN (-2625 500) SIG_NAME T1_GND\g
J 0
(-2615 510);
DISPLAY 0.659574 (-2615 510);
PAINT MONO (-2615 510);
DISPLAY INVISIBLE (-2615 510);
FORCEPROP 1 LAST HDL_POWER T1_GND
J 1
(-2600 375);
DISPLAY 0.872340 (-2600 375);
PAINT GREEN (-2600 375);
FORCEPROP 2 LAST CDS_LIB pure_quanta_power
J 0
(-2625 450);
DISPLAY INVISIBLE (-2625 450);
FORCEPROP 1 LAST PATH I55
J 0
(-2550 450);
DISPLAY 0.872340 (-2550 450);
PAINT AQUA (-2550 450);
DISPLAY INVISIBLE (-2550 450);
FORCEADD TP_TDR_4P_FTS..1
(-2200 650);
FORCEPROP 1 LAST LOCATION X8006
J 0
(-2325 930);
DISPLAY 0.723404 (-2325 930);
PAINT GREEN (-2325 930);
FORCEPROP 0 LAST $SEC 1
J 0
(-2325 1075);
DISPLAY 0.680851 (-2325 1075);
PAINT MONO (-2325 1075);
DISPLAY INVISIBLE (-2325 1075);
FORCEPROP 0 LAST CDS_SEC 1
J 0
(-2325 1075);
DISPLAY 1.021277 (-2325 1075);
DISPLAY INVISIBLE (-2325 1075);
FORCEPROP 0 LASTPIN (-2475 725) $PN 2
J 2
(-2485 735);
DISPLAY 0.680851 (-2485 735);
PAINT MONO (-2485 735);
FORCEPROP 0 LASTPIN (-2475 575) $PN 3
J 2
(-2485 585);
DISPLAY 0.680851 (-2485 585);
PAINT MONO (-2485 585);
FORCEPROP 0 LASTPIN (-1925 725) $PN 1
J 0
(-1915 735);
DISPLAY 0.680851 (-1915 735);
PAINT MONO (-1915 735);
FORCEPROP 0 LASTPIN (-1925 575) $PN 4
J 0
(-1915 585);
DISPLAY 0.680851 (-1915 585);
PAINT MONO (-1915 585);
FORCEPROP 1 LAST MATERIAL EMPTY
J 0
(-2325 835);
DISPLAY 0.723404 (-2325 835);
PAINT GREEN (-2325 835);
FORCEPROP 2 LAST PACK_TYPE TH
J 0
(-2325 975);
DISPLAY 1.021277 (-2325 975);
FORCEPROP 2 LAST VALUE TP_TDR_4P_DIP
J 0
(-2325 1025);
DISPLAY 1.021277 (-2325 1025);
FORCEPROP 2 LAST CDS_LIB pure_quanta
J 0
(-2200 650);
DISPLAY INVISIBLE (-2200 650);
FORCEPROP 1 LAST NEEDS_NO_SIZE TRUE
J 0
(-2200 650);
DISPLAY 0.468085 (-2200 650);
PAINT GREEN (-2200 650);
DISPLAY INVISIBLE (-2200 650);
FORCEPROP 1 LAST PATH I56
J 0
(-2100 830);
DISPLAY 0.723404 (-2100 830);
PAINT GREEN (-2100 830);
DISPLAY INVISIBLE (-2100 830);
FORCEPROP 1 LAST PART_NUMBER TP15
J 0
(-2325 885);
DISPLAY 0.723404 (-2325 885);
PAINT GREEN (-2325 885);
DISPLAY INVISIBLE (-2325 885);
FORCEADD UNIVERSAL_GND..1
(-2625 1075);
FORCEPROP 3 LASTPIN (-2625 1125) SIG_NAME T1_GND\g
J 0
(-2615 1135);
DISPLAY 0.659574 (-2615 1135);
PAINT MONO (-2615 1135);
DISPLAY INVISIBLE (-2615 1135);
FORCEPROP 1 LAST HDL_POWER T1_GND
J 1
(-2600 1000);
DISPLAY 0.872340 (-2600 1000);
PAINT GREEN (-2600 1000);
FORCEPROP 2 LAST CDS_LIB pure_quanta_power
J 0
(-2625 1075);
DISPLAY INVISIBLE (-2625 1075);
FORCEPROP 1 LAST PATH I57
J 0
(-2550 1075);
DISPLAY 0.872340 (-2550 1075);
PAINT AQUA (-2550 1075);
DISPLAY INVISIBLE (-2550 1075);
FORCEADD TP_TDR_4P_FTS..1
(-2200 1300);
FORCEPROP 1 LAST LOCATION X8026
J 0
(-2325 1580);
DISPLAY 0.723404 (-2325 1580);
PAINT GREEN (-2325 1580);
FORCEPROP 0 LAST $SEC 1
J 0
(-2325 1725);
DISPLAY 0.680851 (-2325 1725);
PAINT MONO (-2325 1725);
DISPLAY INVISIBLE (-2325 1725);
FORCEPROP 0 LAST CDS_SEC 1
J 0
(-2325 1725);
DISPLAY 1.021277 (-2325 1725);
DISPLAY INVISIBLE (-2325 1725);
FORCEPROP 0 LASTPIN (-2475 1375) $PN 2
J 2
(-2485 1385);
DISPLAY 0.680851 (-2485 1385);
PAINT MONO (-2485 1385);
FORCEPROP 0 LASTPIN (-2475 1225) $PN 3
J 2
(-2485 1235);
DISPLAY 0.680851 (-2485 1235);
PAINT MONO (-2485 1235);
FORCEPROP 0 LASTPIN (-1925 1375) $PN 1
J 0
(-1915 1385);
DISPLAY 0.680851 (-1915 1385);
PAINT MONO (-1915 1385);
FORCEPROP 0 LASTPIN (-1925 1225) $PN 4
J 0
(-1915 1235);
DISPLAY 0.680851 (-1915 1235);
PAINT MONO (-1915 1235);
FORCEPROP 1 LAST MATERIAL EMPTY
J 0
(-2325 1485);
DISPLAY 0.723404 (-2325 1485);
PAINT GREEN (-2325 1485);
FORCEPROP 2 LAST PACK_TYPE TH
J 0
(-2325 1625);
DISPLAY 1.021277 (-2325 1625);
FORCEPROP 2 LAST VALUE TP_TDR_4P_DIP
J 0
(-2325 1675);
DISPLAY 1.021277 (-2325 1675);
FORCEPROP 2 LAST CDS_LIB pure_quanta
J 0
(-2200 1300);
DISPLAY INVISIBLE (-2200 1300);
FORCEPROP 1 LAST NEEDS_NO_SIZE TRUE
J 0
(-2200 1300);
DISPLAY 0.468085 (-2200 1300);
PAINT GREEN (-2200 1300);
DISPLAY INVISIBLE (-2200 1300);
FORCEPROP 1 LAST PATH I58
J 0
(-2100 1480);
DISPLAY 0.723404 (-2100 1480);
PAINT GREEN (-2100 1480);
DISPLAY INVISIBLE (-2100 1480);
FORCEPROP 1 LAST PART_NUMBER TP15
J 0
(-2325 1535);
DISPLAY 0.723404 (-2325 1535);
PAINT GREEN (-2325 1535);
DISPLAY INVISIBLE (-2325 1535);
FORCEADD UNIVERSAL_GND..1
(-2625 1850);
FORCEPROP 3 LASTPIN (-2625 1900) SIG_NAME T1_GND\g
J 0
(-2615 1910);
DISPLAY 0.659574 (-2615 1910);
PAINT MONO (-2615 1910);
DISPLAY INVISIBLE (-2615 1910);
FORCEPROP 1 LAST HDL_POWER T1_GND
J 1
(-2600 1775);
DISPLAY 0.872340 (-2600 1775);
PAINT GREEN (-2600 1775);
FORCEPROP 2 LAST CDS_LIB pure_quanta_power
J 0
(-2625 1850);
DISPLAY INVISIBLE (-2625 1850);
FORCEPROP 1 LAST PATH I59
J 0
(-2550 1850);
DISPLAY 0.872340 (-2550 1850);
PAINT AQUA (-2550 1850);
DISPLAY INVISIBLE (-2550 1850);
FORCEADD UNIVERSAL_GND..1
(-9000 3550);
FORCEPROP 3 LASTPIN (-9000 3600) SIG_NAME T1_GND\g
J 0
(-8990 3610);
DISPLAY 0.659574 (-8990 3610);
PAINT MONO (-8990 3610);
DISPLAY INVISIBLE (-8990 3610);
FORCEPROP 1 LAST HDL_POWER T1_GND
J 1
(-8975 3475);
DISPLAY 0.872340 (-8975 3475);
PAINT GREEN (-8975 3475);
FORCEPROP 2 LAST CDS_LIB pure_quanta_power
J 0
(-9000 3550);
DISPLAY INVISIBLE (-9000 3550);
FORCEPROP 1 LAST PATH I6
J 0
(-8925 3550);
DISPLAY 0.872340 (-8925 3550);
PAINT AQUA (-8925 3550);
DISPLAY INVISIBLE (-8925 3550);
FORCEADD TP_TDR_4P_FTS..1
(-2200 2075);
FORCEPROP 1 LAST LOCATION X8025
J 0
(-2325 2355);
DISPLAY 0.723404 (-2325 2355);
PAINT GREEN (-2325 2355);
FORCEPROP 0 LAST $SEC 1
J 0
(-2325 2500);
DISPLAY 0.680851 (-2325 2500);
PAINT MONO (-2325 2500);
DISPLAY INVISIBLE (-2325 2500);
FORCEPROP 0 LAST CDS_SEC 1
J 0
(-2325 2500);
DISPLAY 1.021277 (-2325 2500);
DISPLAY INVISIBLE (-2325 2500);
FORCEPROP 0 LASTPIN (-2475 2150) $PN 2
J 2
(-2485 2160);
DISPLAY 0.680851 (-2485 2160);
PAINT MONO (-2485 2160);
FORCEPROP 0 LASTPIN (-2475 2000) $PN 3
J 2
(-2485 2010);
DISPLAY 0.680851 (-2485 2010);
PAINT MONO (-2485 2010);
FORCEPROP 0 LASTPIN (-1925 2150) $PN 1
J 0
(-1915 2160);
DISPLAY 0.680851 (-1915 2160);
PAINT MONO (-1915 2160);
FORCEPROP 0 LASTPIN (-1925 2000) $PN 4
J 0
(-1915 2010);
DISPLAY 0.680851 (-1915 2010);
PAINT MONO (-1915 2010);
FORCEPROP 1 LAST MATERIAL EMPTY
J 0
(-2325 2260);
DISPLAY 0.723404 (-2325 2260);
PAINT GREEN (-2325 2260);
FORCEPROP 2 LAST VALUE TP_TDR_4P_DIP
J 0
(-2325 2450);
DISPLAY 1.021277 (-2325 2450);
FORCEPROP 2 LAST PACK_TYPE TH
J 0
(-2325 2400);
DISPLAY 1.021277 (-2325 2400);
FORCEPROP 2 LAST CDS_LIB pure_quanta
J 0
(-2200 2075);
DISPLAY INVISIBLE (-2200 2075);
FORCEPROP 1 LAST NEEDS_NO_SIZE TRUE
J 0
(-2200 2075);
DISPLAY 0.468085 (-2200 2075);
PAINT GREEN (-2200 2075);
DISPLAY INVISIBLE (-2200 2075);
FORCEPROP 1 LAST PATH I60
J 0
(-2100 2255);
DISPLAY 0.723404 (-2100 2255);
PAINT GREEN (-2100 2255);
DISPLAY INVISIBLE (-2100 2255);
FORCEPROP 1 LAST PART_NUMBER TP15
J 0
(-2325 2310);
DISPLAY 0.723404 (-2325 2310);
PAINT GREEN (-2325 2310);
DISPLAY INVISIBLE (-2325 2310);
FORCEADD TP_TDR_4P_FTS..1
R 4
(-3700 3500);
FORCEPROP 1 LAST LOCATION X10
J 0
(-3825 3795);
DISPLAY 0.723404 (-3825 3795);
PAINT GREEN (-3825 3795);
FORCEPROP 0 LAST $SEC 1
J 0
(-3825 3925);
DISPLAY 0.680851 (-3825 3925);
PAINT MONO (-3825 3925);
DISPLAY INVISIBLE (-3825 3925);
FORCEPROP 0 LAST CDS_SEC 1
J 0
(-3825 3925);
DISPLAY 1.021277 (-3825 3925);
DISPLAY INVISIBLE (-3825 3925);
FORCEPROP 0 LASTPIN (-3425 3425) $PN 2
J 0
(-3415 3435);
DISPLAY 0.680851 (-3415 3435);
PAINT MONO (-3415 3435);
FORCEPROP 0 LASTPIN (-3425 3575) $PN 3
J 0
(-3415 3585);
DISPLAY 0.680851 (-3415 3585);
PAINT MONO (-3415 3585);
FORCEPROP 0 LASTPIN (-3975 3425) $PN 1
J 2
(-3985 3435);
DISPLAY 0.680851 (-3985 3435);
PAINT MONO (-3985 3435);
FORCEPROP 0 LASTPIN (-3975 3575) $PN 4
J 2
(-3985 3585);
DISPLAY 0.680851 (-3985 3585);
PAINT MONO (-3985 3585);
FORCEPROP 1 LAST MATERIAL EMPTY
J 0
(-3825 3890);
DISPLAY 0.723404 (-3825 3890);
PAINT GREEN (-3825 3890);
FORCEPROP 2 LAST VALUE TP_TDR_4P_DIP
J 0
(-3825 3700);
DISPLAY 1.021277 (-3825 3700);
FORCEPROP 2 LAST PACK_TYPE TH
J 0
(-3825 3750);
DISPLAY 1.021277 (-3825 3750);
FORCEPROP 2 LAST CDS_LIB pure_quanta
R 2
J 0
(-3700 3500);
DISPLAY INVISIBLE (-3700 3500);
FORCEPROP 1 LAST NEEDS_NO_SIZE TRUE
R 2
J 0
(-3700 3500);
DISPLAY 0.468085 (-3700 3500);
PAINT GREEN (-3700 3500);
DISPLAY INVISIBLE (-3700 3500);
FORCEPROP 1 LAST PATH I61
R 2
J 0
(-3800 3320);
DISPLAY 0.723404 (-3800 3320);
PAINT GREEN (-3800 3320);
DISPLAY INVISIBLE (-3800 3320);
FORCEPROP 1 LAST PART_NUMBER TP15
J 0
(-3825 3840);
DISPLAY 0.723404 (-3825 3840);
PAINT GREEN (-3825 3840);
DISPLAY INVISIBLE (-3825 3840);
FORCEADD TP_TDR_4P_FTS..1
R 4
(-3700 4275);
FORCEPROP 1 LAST LOCATION X9
J 0
(-3825 4570);
DISPLAY 0.723404 (-3825 4570);
PAINT GREEN (-3825 4570);
FORCEPROP 0 LAST $SEC 1
J 0
(-3825 4700);
DISPLAY 0.680851 (-3825 4700);
PAINT MONO (-3825 4700);
DISPLAY INVISIBLE (-3825 4700);
FORCEPROP 0 LAST CDS_SEC 1
J 0
(-3825 4700);
DISPLAY 1.021277 (-3825 4700);
DISPLAY INVISIBLE (-3825 4700);
FORCEPROP 0 LASTPIN (-3425 4200) $PN 2
J 0
(-3415 4210);
DISPLAY 0.680851 (-3415 4210);
PAINT MONO (-3415 4210);
FORCEPROP 0 LASTPIN (-3425 4350) $PN 3
J 0
(-3415 4360);
DISPLAY 0.680851 (-3415 4360);
PAINT MONO (-3415 4360);
FORCEPROP 0 LASTPIN (-3975 4200) $PN 1
J 2
(-3985 4210);
DISPLAY 0.680851 (-3985 4210);
PAINT MONO (-3985 4210);
FORCEPROP 0 LASTPIN (-3975 4350) $PN 4
J 2
(-3985 4360);
DISPLAY 0.680851 (-3985 4360);
PAINT MONO (-3985 4360);
FORCEPROP 2 LAST VALUE TP_TDR_4P_DIP
J 0
(-3825 4475);
DISPLAY 1.021277 (-3825 4475);
FORCEPROP 1 LAST MATERIAL EMPTY
J 0
(-3825 4665);
DISPLAY 0.723404 (-3825 4665);
PAINT GREEN (-3825 4665);
FORCEPROP 2 LAST PACK_TYPE TH
J 0
(-3825 4525);
DISPLAY 1.021277 (-3825 4525);
FORCEPROP 2 LAST CDS_LIB pure_quanta
R 2
J 0
(-3700 4275);
DISPLAY INVISIBLE (-3700 4275);
FORCEPROP 1 LAST NEEDS_NO_SIZE TRUE
R 2
J 0
(-3700 4275);
DISPLAY 0.468085 (-3700 4275);
PAINT GREEN (-3700 4275);
DISPLAY INVISIBLE (-3700 4275);
FORCEPROP 1 LAST PATH I62
R 2
J 0
(-3800 4095);
DISPLAY 0.723404 (-3800 4095);
PAINT GREEN (-3800 4095);
DISPLAY INVISIBLE (-3800 4095);
FORCEPROP 1 LAST PART_NUMBER TP15
J 0
(-3825 4615);
DISPLAY 0.723404 (-3825 4615);
PAINT GREEN (-3825 4615);
DISPLAY INVISIBLE (-3825 4615);
FORCEADD UNIVERSAL_GND..1
(-3300 3275);
FORCEPROP 3 LASTPIN (-3300 3325) SIG_NAME T1_GND\g
J 0
(-3290 3335);
DISPLAY 0.659574 (-3290 3335);
PAINT MONO (-3290 3335);
DISPLAY INVISIBLE (-3290 3335);
FORCEPROP 1 LAST HDL_POWER T1_GND
J 1
(-3275 3200);
DISPLAY 0.872340 (-3275 3200);
PAINT GREEN (-3275 3200);
FORCEPROP 2 LAST CDS_LIB pure_quanta_power
J 0
(-3300 3275);
DISPLAY INVISIBLE (-3300 3275);
FORCEPROP 1 LAST PATH I63
J 0
(-3225 3275);
DISPLAY 0.872340 (-3225 3275);
PAINT AQUA (-3225 3275);
DISPLAY INVISIBLE (-3225 3275);
FORCEADD UNIVERSAL_GND..1
(-3300 4050);
FORCEPROP 3 LASTPIN (-3300 4100) SIG_NAME T1_GND\g
J 0
(-3290 4110);
DISPLAY 0.659574 (-3290 4110);
PAINT MONO (-3290 4110);
DISPLAY INVISIBLE (-3290 4110);
FORCEPROP 1 LAST HDL_POWER T1_GND
J 1
(-3275 3975);
DISPLAY 0.872340 (-3275 3975);
PAINT GREEN (-3275 3975);
FORCEPROP 2 LAST CDS_LIB pure_quanta_power
J 0
(-3300 4050);
DISPLAY INVISIBLE (-3300 4050);
FORCEPROP 1 LAST PATH I64
J 0
(-3225 4050);
DISPLAY 0.872340 (-3225 4050);
PAINT AQUA (-3225 4050);
DISPLAY INVISIBLE (-3225 4050);
FORCEADD UNIVERSAL_GND..1
(-2625 2525);
FORCEPROP 3 LASTPIN (-2625 2575) SIG_NAME T1_GND\g
J 0
(-2615 2585);
DISPLAY 0.659574 (-2615 2585);
PAINT MONO (-2615 2585);
DISPLAY INVISIBLE (-2615 2585);
FORCEPROP 1 LAST HDL_POWER T1_GND
J 1
(-2600 2450);
DISPLAY 0.872340 (-2600 2450);
PAINT GREEN (-2600 2450);
FORCEPROP 2 LAST CDS_LIB pure_quanta_power
J 0
(-2625 2525);
DISPLAY INVISIBLE (-2625 2525);
FORCEPROP 1 LAST PATH I65
J 0
(-2550 2525);
DISPLAY 0.872340 (-2550 2525);
PAINT AQUA (-2550 2525);
DISPLAY INVISIBLE (-2550 2525);
FORCEADD TP_TDR_4P_FTS..1
(-2200 2750);
FORCEPROP 1 LAST LOCATION X8005
J 0
(-2325 3030);
DISPLAY 0.723404 (-2325 3030);
PAINT GREEN (-2325 3030);
FORCEPROP 0 LAST $SEC 1
J 0
(-2325 3175);
DISPLAY 0.680851 (-2325 3175);
PAINT MONO (-2325 3175);
DISPLAY INVISIBLE (-2325 3175);
FORCEPROP 0 LAST CDS_SEC 1
J 0
(-2325 3175);
DISPLAY 1.021277 (-2325 3175);
DISPLAY INVISIBLE (-2325 3175);
FORCEPROP 0 LASTPIN (-2475 2825) $PN 2
J 2
(-2485 2835);
DISPLAY 0.680851 (-2485 2835);
PAINT MONO (-2485 2835);
FORCEPROP 0 LASTPIN (-2475 2675) $PN 3
J 2
(-2485 2685);
DISPLAY 0.680851 (-2485 2685);
PAINT MONO (-2485 2685);
FORCEPROP 0 LASTPIN (-1925 2825) $PN 1
J 0
(-1915 2835);
DISPLAY 0.680851 (-1915 2835);
PAINT MONO (-1915 2835);
FORCEPROP 0 LASTPIN (-1925 2675) $PN 4
J 0
(-1915 2685);
DISPLAY 0.680851 (-1915 2685);
PAINT MONO (-1915 2685);
FORCEPROP 1 LAST MATERIAL EMPTY
J 0
(-2325 2935);
DISPLAY 0.723404 (-2325 2935);
PAINT GREEN (-2325 2935);
FORCEPROP 2 LAST VALUE TP_TDR_4P_DIP
J 0
(-2325 3125);
DISPLAY 1.021277 (-2325 3125);
FORCEPROP 2 LAST PACK_TYPE TH
J 0
(-2325 3075);
DISPLAY 1.021277 (-2325 3075);
FORCEPROP 2 LAST CDS_LIB pure_quanta
J 0
(-2200 2750);
DISPLAY INVISIBLE (-2200 2750);
FORCEPROP 1 LAST NEEDS_NO_SIZE TRUE
J 0
(-2200 2750);
DISPLAY 0.468085 (-2200 2750);
PAINT GREEN (-2200 2750);
DISPLAY INVISIBLE (-2200 2750);
FORCEPROP 1 LAST PATH I66
J 0
(-2100 2930);
DISPLAY 0.723404 (-2100 2930);
PAINT GREEN (-2100 2930);
DISPLAY INVISIBLE (-2100 2930);
FORCEPROP 1 LAST PART_NUMBER TP15
J 0
(-2325 2985);
DISPLAY 0.723404 (-2325 2985);
PAINT GREEN (-2325 2985);
DISPLAY INVISIBLE (-2325 2985);
FORCEADD UNIVERSAL_GND..1
(-2625 3300);
FORCEPROP 3 LASTPIN (-2625 3350) SIG_NAME T1_GND\g
J 0
(-2615 3360);
DISPLAY 0.659574 (-2615 3360);
PAINT MONO (-2615 3360);
DISPLAY INVISIBLE (-2615 3360);
FORCEPROP 1 LAST HDL_POWER T1_GND
J 1
(-2600 3225);
DISPLAY 0.872340 (-2600 3225);
PAINT GREEN (-2600 3225);
FORCEPROP 2 LAST CDS_LIB pure_quanta_power
J 0
(-2625 3300);
DISPLAY INVISIBLE (-2625 3300);
FORCEPROP 1 LAST PATH I67
J 0
(-2550 3300);
DISPLAY 0.872340 (-2550 3300);
PAINT AQUA (-2550 3300);
DISPLAY INVISIBLE (-2550 3300);
FORCEADD TP_TDR_4P_FTS..1
(-2200 3525);
FORCEPROP 1 LAST LOCATION X8004
J 0
(-2325 3805);
DISPLAY 0.723404 (-2325 3805);
PAINT GREEN (-2325 3805);
FORCEPROP 0 LAST $SEC 1
J 0
(-2325 3950);
DISPLAY 0.680851 (-2325 3950);
PAINT MONO (-2325 3950);
DISPLAY INVISIBLE (-2325 3950);
FORCEPROP 0 LAST CDS_SEC 1
J 0
(-2325 3950);
DISPLAY 1.021277 (-2325 3950);
DISPLAY INVISIBLE (-2325 3950);
FORCEPROP 0 LASTPIN (-2475 3600) $PN 2
J 2
(-2485 3610);
DISPLAY 0.680851 (-2485 3610);
PAINT MONO (-2485 3610);
FORCEPROP 0 LASTPIN (-2475 3450) $PN 3
J 2
(-2485 3460);
DISPLAY 0.680851 (-2485 3460);
PAINT MONO (-2485 3460);
FORCEPROP 0 LASTPIN (-1925 3600) $PN 1
J 0
(-1915 3610);
DISPLAY 0.680851 (-1915 3610);
PAINT MONO (-1915 3610);
FORCEPROP 0 LASTPIN (-1925 3450) $PN 4
J 0
(-1915 3460);
DISPLAY 0.680851 (-1915 3460);
PAINT MONO (-1915 3460);
FORCEPROP 2 LAST VALUE TP_TDR_4P_DIP
J 0
(-2325 3900);
DISPLAY 1.021277 (-2325 3900);
FORCEPROP 2 LAST PACK_TYPE TH
J 0
(-2325 3850);
DISPLAY 1.021277 (-2325 3850);
FORCEPROP 1 LAST MATERIAL EMPTY
J 0
(-2325 3710);
DISPLAY 0.723404 (-2325 3710);
PAINT GREEN (-2325 3710);
FORCEPROP 2 LAST CDS_LIB pure_quanta
J 0
(-2200 3525);
DISPLAY INVISIBLE (-2200 3525);
FORCEPROP 1 LAST NEEDS_NO_SIZE TRUE
J 0
(-2200 3525);
DISPLAY 0.468085 (-2200 3525);
PAINT GREEN (-2200 3525);
DISPLAY INVISIBLE (-2200 3525);
FORCEPROP 1 LAST PATH I68
J 0
(-2100 3705);
DISPLAY 0.723404 (-2100 3705);
PAINT GREEN (-2100 3705);
DISPLAY INVISIBLE (-2100 3705);
FORCEPROP 1 LAST PART_NUMBER TP15
J 0
(-2325 3760);
DISPLAY 0.723404 (-2325 3760);
PAINT GREEN (-2325 3760);
DISPLAY INVISIBLE (-2325 3760);
FORCEADD UNIVERSAL_GND..1
(-2625 4075);
FORCEPROP 3 LASTPIN (-2625 4125) SIG_NAME T1_GND\g
J 0
(-2615 4135);
DISPLAY 0.659574 (-2615 4135);
PAINT MONO (-2615 4135);
DISPLAY INVISIBLE (-2615 4135);
FORCEPROP 1 LAST HDL_POWER T1_GND
J 1
(-2600 4000);
DISPLAY 0.872340 (-2600 4000);
PAINT GREEN (-2600 4000);
FORCEPROP 2 LAST CDS_LIB pure_quanta_power
J 0
(-2625 4075);
DISPLAY INVISIBLE (-2625 4075);
FORCEPROP 1 LAST PATH I69
J 0
(-2550 4075);
DISPLAY 0.872340 (-2550 4075);
PAINT AQUA (-2550 4075);
DISPLAY INVISIBLE (-2550 4075);
FORCEADD UNIVERSAL_GND..1
(-9000 4075);
FORCEPROP 3 LASTPIN (-9000 4125) SIG_NAME T1_GND\g
J 0
(-8990 4135);
DISPLAY 0.659574 (-8990 4135);
PAINT MONO (-8990 4135);
DISPLAY INVISIBLE (-8990 4135);
FORCEPROP 1 LAST HDL_POWER T1_GND
J 1
(-8975 4000);
DISPLAY 0.872340 (-8975 4000);
PAINT GREEN (-8975 4000);
FORCEPROP 2 LAST CDS_LIB pure_quanta_power
J 0
(-9000 4075);
DISPLAY INVISIBLE (-9000 4075);
FORCEPROP 1 LAST PATH I7
J 0
(-8925 4075);
DISPLAY 0.872340 (-8925 4075);
PAINT AQUA (-8925 4075);
DISPLAY INVISIBLE (-8925 4075);
FORCEADD TP_TDR_4P_FTS..1
(-2200 4300);
FORCEPROP 1 LAST LOCATION X8003
J 0
(-2325 4580);
DISPLAY 0.723404 (-2325 4580);
PAINT GREEN (-2325 4580);
FORCEPROP 0 LAST $SEC 1
J 0
(-2325 4725);
DISPLAY 0.680851 (-2325 4725);
PAINT MONO (-2325 4725);
DISPLAY INVISIBLE (-2325 4725);
FORCEPROP 0 LAST CDS_SEC 1
J 0
(-2325 4725);
DISPLAY 1.021277 (-2325 4725);
DISPLAY INVISIBLE (-2325 4725);
FORCEPROP 0 LASTPIN (-2475 4375) $PN 2
J 2
(-2485 4385);
DISPLAY 0.680851 (-2485 4385);
PAINT MONO (-2485 4385);
FORCEPROP 0 LASTPIN (-2475 4225) $PN 3
J 2
(-2485 4235);
DISPLAY 0.680851 (-2485 4235);
PAINT MONO (-2485 4235);
FORCEPROP 0 LASTPIN (-1925 4375) $PN 1
J 0
(-1915 4385);
DISPLAY 0.680851 (-1915 4385);
PAINT MONO (-1915 4385);
FORCEPROP 0 LASTPIN (-1925 4225) $PN 4
J 0
(-1915 4235);
DISPLAY 0.680851 (-1915 4235);
PAINT MONO (-1915 4235);
FORCEPROP 2 LAST PACK_TYPE TH
J 0
(-2325 4625);
DISPLAY 1.021277 (-2325 4625);
FORCEPROP 2 LAST VALUE TP_TDR_4P_DIP
J 0
(-2325 4675);
DISPLAY 1.021277 (-2325 4675);
FORCEPROP 1 LAST MATERIAL EMPTY
J 0
(-2325 4485);
DISPLAY 0.723404 (-2325 4485);
PAINT GREEN (-2325 4485);
FORCEPROP 2 LAST CDS_LIB pure_quanta
J 0
(-2200 4300);
DISPLAY INVISIBLE (-2200 4300);
FORCEPROP 1 LAST NEEDS_NO_SIZE TRUE
J 0
(-2200 4300);
DISPLAY 0.468085 (-2200 4300);
PAINT GREEN (-2200 4300);
DISPLAY INVISIBLE (-2200 4300);
FORCEPROP 1 LAST PATH I70
J 0
(-2100 4480);
DISPLAY 0.723404 (-2100 4480);
PAINT GREEN (-2100 4480);
DISPLAY INVISIBLE (-2100 4480);
FORCEPROP 1 LAST PART_NUMBER TP15
J 0
(-2325 4535);
DISPLAY 0.723404 (-2325 4535);
PAINT GREEN (-2325 4535);
DISPLAY INVISIBLE (-2325 4535);
FORCEADD UNIVERSAL_GND..1
(-475 450);
FORCEPROP 3 LASTPIN (-475 500) SIG_NAME T1_GND\g
J 0
(-465 510);
DISPLAY 0.659574 (-465 510);
PAINT MONO (-465 510);
DISPLAY INVISIBLE (-465 510);
FORCEPROP 1 LAST HDL_POWER T1_GND
J 1
(-450 375);
DISPLAY 0.872340 (-450 375);
PAINT GREEN (-450 375);
FORCEPROP 2 LAST CDS_LIB pure_quanta_power
J 0
(-475 450);
DISPLAY INVISIBLE (-475 450);
FORCEPROP 1 LAST PATH I71
J 0
(-400 450);
DISPLAY 0.872340 (-400 450);
PAINT AQUA (-400 450);
DISPLAY INVISIBLE (-400 450);
FORCEADD UNIVERSAL_GND..1
(-475 1075);
FORCEPROP 3 LASTPIN (-475 1125) SIG_NAME T1_GND\g
J 0
(-465 1135);
DISPLAY 0.659574 (-465 1135);
PAINT MONO (-465 1135);
DISPLAY INVISIBLE (-465 1135);
FORCEPROP 1 LAST HDL_POWER T1_GND
J 1
(-450 1000);
DISPLAY 0.872340 (-450 1000);
PAINT GREEN (-450 1000);
FORCEPROP 2 LAST CDS_LIB pure_quanta_power
J 0
(-475 1075);
DISPLAY INVISIBLE (-475 1075);
FORCEPROP 1 LAST PATH I72
J 0
(-400 1075);
DISPLAY 0.872340 (-400 1075);
PAINT AQUA (-400 1075);
DISPLAY INVISIBLE (-400 1075);
FORCEADD TP_TDR_4P_FTS..1
R 4
(-875 1300);
FORCEPROP 1 LAST LOCATION X8028
J 0
(-1000 1595);
DISPLAY 0.723404 (-1000 1595);
PAINT GREEN (-1000 1595);
FORCEPROP 0 LAST $SEC 1
J 0
(-1000 1725);
DISPLAY 0.680851 (-1000 1725);
PAINT MONO (-1000 1725);
DISPLAY INVISIBLE (-1000 1725);
FORCEPROP 0 LAST CDS_SEC 1
J 0
(-1000 1725);
DISPLAY 1.021277 (-1000 1725);
DISPLAY INVISIBLE (-1000 1725);
FORCEPROP 0 LASTPIN (-600 1225) $PN 2
J 0
(-590 1235);
DISPLAY 0.680851 (-590 1235);
PAINT MONO (-590 1235);
FORCEPROP 0 LASTPIN (-600 1375) $PN 3
J 0
(-590 1385);
DISPLAY 0.680851 (-590 1385);
PAINT MONO (-590 1385);
FORCEPROP 0 LASTPIN (-1150 1225) $PN 1
J 2
(-1160 1235);
DISPLAY 0.680851 (-1160 1235);
PAINT MONO (-1160 1235);
FORCEPROP 0 LASTPIN (-1150 1375) $PN 4
J 2
(-1160 1385);
DISPLAY 0.680851 (-1160 1385);
PAINT MONO (-1160 1385);
FORCEPROP 2 LAST VALUE TP_TDR_4P_DIP
J 0
(-1000 1500);
DISPLAY 1.021277 (-1000 1500);
FORCEPROP 2 LAST PACK_TYPE TH
J 0
(-1000 1550);
DISPLAY 1.021277 (-1000 1550);
FORCEPROP 1 LAST MATERIAL EMPTY
J 0
(-1000 1690);
DISPLAY 0.723404 (-1000 1690);
PAINT GREEN (-1000 1690);
FORCEPROP 2 LAST CDS_LIB pure_quanta
R 2
J 0
(-875 1300);
DISPLAY INVISIBLE (-875 1300);
FORCEPROP 1 LAST NEEDS_NO_SIZE TRUE
R 2
J 0
(-875 1300);
DISPLAY 0.468085 (-875 1300);
PAINT GREEN (-875 1300);
DISPLAY INVISIBLE (-875 1300);
FORCEPROP 1 LAST PATH I73
R 2
J 0
(-975 1120);
DISPLAY 0.723404 (-975 1120);
PAINT GREEN (-975 1120);
DISPLAY INVISIBLE (-975 1120);
FORCEPROP 1 LAST PART_NUMBER TP15
J 0
(-1000 1640);
DISPLAY 0.723404 (-1000 1640);
PAINT GREEN (-1000 1640);
DISPLAY INVISIBLE (-1000 1640);
FORCEADD TP_TDR_4P_FTS..1
R 4
(-875 2075);
FORCEPROP 1 LAST LOCATION X8027
J 0
(-1000 2370);
DISPLAY 0.723404 (-1000 2370);
PAINT GREEN (-1000 2370);
FORCEPROP 0 LAST $SEC 1
J 0
(-1000 2500);
DISPLAY 0.680851 (-1000 2500);
PAINT MONO (-1000 2500);
DISPLAY INVISIBLE (-1000 2500);
FORCEPROP 0 LAST CDS_SEC 1
J 0
(-1000 2500);
DISPLAY 1.021277 (-1000 2500);
DISPLAY INVISIBLE (-1000 2500);
FORCEPROP 0 LASTPIN (-600 2000) $PN 2
J 0
(-590 2010);
DISPLAY 0.680851 (-590 2010);
PAINT MONO (-590 2010);
FORCEPROP 0 LASTPIN (-600 2150) $PN 3
J 0
(-590 2160);
DISPLAY 0.680851 (-590 2160);
PAINT MONO (-590 2160);
FORCEPROP 0 LASTPIN (-1150 2000) $PN 1
J 2
(-1160 2010);
DISPLAY 0.680851 (-1160 2010);
PAINT MONO (-1160 2010);
FORCEPROP 0 LASTPIN (-1150 2150) $PN 4
J 2
(-1160 2160);
DISPLAY 0.680851 (-1160 2160);
PAINT MONO (-1160 2160);
FORCEPROP 2 LAST VALUE TP_TDR_4P_DIP
J 0
(-1000 2275);
DISPLAY 1.021277 (-1000 2275);
FORCEPROP 1 LAST MATERIAL EMPTY
J 0
(-1000 2465);
DISPLAY 0.723404 (-1000 2465);
PAINT GREEN (-1000 2465);
FORCEPROP 2 LAST PACK_TYPE TH
J 0
(-1000 2325);
DISPLAY 1.021277 (-1000 2325);
FORCEPROP 2 LAST CDS_LIB pure_quanta
R 2
J 0
(-875 2075);
DISPLAY INVISIBLE (-875 2075);
FORCEPROP 1 LAST NEEDS_NO_SIZE TRUE
R 2
J 0
(-875 2075);
DISPLAY 0.468085 (-875 2075);
PAINT GREEN (-875 2075);
DISPLAY INVISIBLE (-875 2075);
FORCEPROP 1 LAST PATH I74
R 2
J 0
(-975 1895);
DISPLAY 0.723404 (-975 1895);
PAINT GREEN (-975 1895);
DISPLAY INVISIBLE (-975 1895);
FORCEPROP 1 LAST PART_NUMBER TP15
J 0
(-1000 2415);
DISPLAY 0.723404 (-1000 2415);
PAINT GREEN (-1000 2415);
DISPLAY INVISIBLE (-1000 2415);
FORCEADD UNIVERSAL_GND..1
(-475 1850);
FORCEPROP 3 LASTPIN (-475 1900) SIG_NAME T1_GND\g
J 0
(-465 1910);
DISPLAY 0.659574 (-465 1910);
PAINT MONO (-465 1910);
DISPLAY INVISIBLE (-465 1910);
FORCEPROP 1 LAST HDL_POWER T1_GND
J 1
(-450 1775);
DISPLAY 0.872340 (-450 1775);
PAINT GREEN (-450 1775);
FORCEPROP 2 LAST CDS_LIB pure_quanta_power
J 0
(-475 1850);
DISPLAY INVISIBLE (-475 1850);
FORCEPROP 1 LAST PATH I75
J 0
(-400 1850);
DISPLAY 0.872340 (-400 1850);
PAINT AQUA (-400 1850);
DISPLAY INVISIBLE (-400 1850);
FORCEADD TP_TDR_4P_FTS..1
R 4
(-875 2750);
FORCEPROP 1 LAST LOCATION X8011
J 0
(-1000 3045);
DISPLAY 0.723404 (-1000 3045);
PAINT GREEN (-1000 3045);
FORCEPROP 0 LAST $SEC 1
J 0
(-1000 3175);
DISPLAY 0.680851 (-1000 3175);
PAINT MONO (-1000 3175);
DISPLAY INVISIBLE (-1000 3175);
FORCEPROP 0 LAST CDS_SEC 1
J 0
(-1000 3175);
DISPLAY 1.021277 (-1000 3175);
DISPLAY INVISIBLE (-1000 3175);
FORCEPROP 0 LASTPIN (-600 2675) $PN 2
J 0
(-590 2685);
DISPLAY 0.680851 (-590 2685);
PAINT MONO (-590 2685);
FORCEPROP 0 LASTPIN (-600 2825) $PN 3
J 0
(-590 2835);
DISPLAY 0.680851 (-590 2835);
PAINT MONO (-590 2835);
FORCEPROP 0 LASTPIN (-1150 2675) $PN 1
J 2
(-1160 2685);
DISPLAY 0.680851 (-1160 2685);
PAINT MONO (-1160 2685);
FORCEPROP 0 LASTPIN (-1150 2825) $PN 4
J 2
(-1160 2835);
DISPLAY 0.680851 (-1160 2835);
PAINT MONO (-1160 2835);
FORCEPROP 2 LAST VALUE TP_TDR_4P_DIP
J 0
(-1000 2950);
DISPLAY 1.021277 (-1000 2950);
FORCEPROP 2 LAST PACK_TYPE TH
J 0
(-1000 3000);
DISPLAY 1.021277 (-1000 3000);
FORCEPROP 1 LAST MATERIAL EMPTY
J 0
(-1000 3140);
DISPLAY 0.723404 (-1000 3140);
PAINT GREEN (-1000 3140);
FORCEPROP 2 LAST CDS_LIB pure_quanta
R 2
J 0
(-875 2750);
DISPLAY INVISIBLE (-875 2750);
FORCEPROP 1 LAST NEEDS_NO_SIZE TRUE
R 2
J 0
(-875 2750);
DISPLAY 0.468085 (-875 2750);
PAINT GREEN (-875 2750);
DISPLAY INVISIBLE (-875 2750);
FORCEPROP 1 LAST PATH I76
R 2
J 0
(-975 2570);
DISPLAY 0.723404 (-975 2570);
PAINT GREEN (-975 2570);
DISPLAY INVISIBLE (-975 2570);
FORCEPROP 1 LAST PART_NUMBER TP15
J 0
(-1000 3090);
DISPLAY 0.723404 (-1000 3090);
PAINT GREEN (-1000 3090);
DISPLAY INVISIBLE (-1000 3090);
FORCEADD UNIVERSAL_GND..1
(-475 2525);
FORCEPROP 3 LASTPIN (-475 2575) SIG_NAME T1_GND\g
J 0
(-465 2585);
DISPLAY 0.659574 (-465 2585);
PAINT MONO (-465 2585);
DISPLAY INVISIBLE (-465 2585);
FORCEPROP 1 LAST HDL_POWER T1_GND
J 1
(-450 2450);
DISPLAY 0.872340 (-450 2450);
PAINT GREEN (-450 2450);
FORCEPROP 2 LAST CDS_LIB pure_quanta_power
J 0
(-475 2525);
DISPLAY INVISIBLE (-475 2525);
FORCEPROP 1 LAST PATH I77
J 0
(-400 2525);
DISPLAY 0.872340 (-400 2525);
PAINT AQUA (-400 2525);
DISPLAY INVISIBLE (-400 2525);
FORCEADD TP_TDR_4P_FTS..1
R 4
(-875 3525);
FORCEPROP 1 LAST LOCATION X8010
J 0
(-1000 3820);
DISPLAY 0.723404 (-1000 3820);
PAINT GREEN (-1000 3820);
FORCEPROP 0 LAST $SEC 1
J 0
(-1000 3950);
DISPLAY 0.680851 (-1000 3950);
PAINT MONO (-1000 3950);
DISPLAY INVISIBLE (-1000 3950);
FORCEPROP 0 LAST CDS_SEC 1
J 0
(-1000 3950);
DISPLAY 1.021277 (-1000 3950);
DISPLAY INVISIBLE (-1000 3950);
FORCEPROP 0 LASTPIN (-600 3450) $PN 2
J 0
(-590 3460);
DISPLAY 0.680851 (-590 3460);
PAINT MONO (-590 3460);
FORCEPROP 0 LASTPIN (-600 3600) $PN 3
J 0
(-590 3610);
DISPLAY 0.680851 (-590 3610);
PAINT MONO (-590 3610);
FORCEPROP 0 LASTPIN (-1150 3450) $PN 1
J 2
(-1160 3460);
DISPLAY 0.680851 (-1160 3460);
PAINT MONO (-1160 3460);
FORCEPROP 0 LASTPIN (-1150 3600) $PN 4
J 2
(-1160 3610);
DISPLAY 0.680851 (-1160 3610);
PAINT MONO (-1160 3610);
FORCEPROP 1 LAST MATERIAL EMPTY
J 0
(-1000 3915);
DISPLAY 0.723404 (-1000 3915);
PAINT GREEN (-1000 3915);
FORCEPROP 2 LAST PACK_TYPE TH
J 0
(-1000 3775);
DISPLAY 1.021277 (-1000 3775);
FORCEPROP 2 LAST VALUE TP_TDR_4P_DIP
J 0
(-1000 3725);
DISPLAY 1.021277 (-1000 3725);
FORCEPROP 2 LAST CDS_LIB pure_quanta
R 2
J 0
(-875 3525);
DISPLAY INVISIBLE (-875 3525);
FORCEPROP 1 LAST NEEDS_NO_SIZE TRUE
R 2
J 0
(-875 3525);
DISPLAY 0.468085 (-875 3525);
PAINT GREEN (-875 3525);
DISPLAY INVISIBLE (-875 3525);
FORCEPROP 1 LAST PATH I78
R 2
J 0
(-975 3345);
DISPLAY 0.723404 (-975 3345);
PAINT GREEN (-975 3345);
DISPLAY INVISIBLE (-975 3345);
FORCEPROP 1 LAST PART_NUMBER TP15
J 0
(-1000 3865);
DISPLAY 0.723404 (-1000 3865);
PAINT GREEN (-1000 3865);
DISPLAY INVISIBLE (-1000 3865);
FORCEADD TP_TDR_4P_FTS..1
R 4
(-875 4300);
FORCEPROP 1 LAST LOCATION X8009
J 0
(-1000 4595);
DISPLAY 0.723404 (-1000 4595);
PAINT GREEN (-1000 4595);
FORCEPROP 0 LAST $SEC 1
J 0
(-1000 4725);
DISPLAY 0.680851 (-1000 4725);
PAINT MONO (-1000 4725);
DISPLAY INVISIBLE (-1000 4725);
FORCEPROP 0 LAST CDS_SEC 1
J 0
(-1000 4725);
DISPLAY 1.021277 (-1000 4725);
DISPLAY INVISIBLE (-1000 4725);
FORCEPROP 0 LASTPIN (-600 4225) $PN 2
J 0
(-590 4235);
DISPLAY 0.680851 (-590 4235);
PAINT MONO (-590 4235);
FORCEPROP 0 LASTPIN (-600 4375) $PN 3
J 0
(-590 4385);
DISPLAY 0.680851 (-590 4385);
PAINT MONO (-590 4385);
FORCEPROP 0 LASTPIN (-1150 4225) $PN 1
J 2
(-1160 4235);
DISPLAY 0.680851 (-1160 4235);
PAINT MONO (-1160 4235);
FORCEPROP 0 LASTPIN (-1150 4375) $PN 4
J 2
(-1160 4385);
DISPLAY 0.680851 (-1160 4385);
PAINT MONO (-1160 4385);
FORCEPROP 2 LAST VALUE TP_TDR_4P_DIP
J 0
(-1000 4500);
DISPLAY 1.021277 (-1000 4500);
FORCEPROP 1 LAST MATERIAL EMPTY
J 0
(-1000 4690);
DISPLAY 0.723404 (-1000 4690);
PAINT GREEN (-1000 4690);
FORCEPROP 2 LAST PACK_TYPE TH
J 0
(-1000 4550);
DISPLAY 1.021277 (-1000 4550);
FORCEPROP 2 LAST CDS_LIB pure_quanta
R 2
J 0
(-875 4300);
DISPLAY INVISIBLE (-875 4300);
FORCEPROP 1 LAST NEEDS_NO_SIZE TRUE
R 2
J 0
(-875 4300);
DISPLAY 0.468085 (-875 4300);
PAINT GREEN (-875 4300);
DISPLAY INVISIBLE (-875 4300);
FORCEPROP 1 LAST PATH I79
R 2
J 0
(-975 4120);
DISPLAY 0.723404 (-975 4120);
PAINT GREEN (-975 4120);
DISPLAY INVISIBLE (-975 4120);
FORCEPROP 1 LAST PART_NUMBER TP15
J 0
(-1000 4640);
DISPLAY 0.723404 (-1000 4640);
PAINT GREEN (-1000 4640);
DISPLAY INVISIBLE (-1000 4640);
FORCEADD TDR_3P..2
(-8675 3250);
FORCEPROP 1 LAST LOCATION DB13
J 2
(-8650 3450);
DISPLAY 0.872340 (-8650 3450);
PAINT PINK (-8650 3450);
FORCEPROP 0 LAST $SEC 1
J 0
(-8650 3500);
DISPLAY 0.680851 (-8650 3500);
PAINT MONO (-8650 3500);
DISPLAY INVISIBLE (-8650 3500);
FORCEPROP 0 LAST CDS_SEC 1
J 0
(-8650 3500);
DISPLAY 1.021277 (-8650 3500);
DISPLAY INVISIBLE (-8650 3500);
FORCEPROP 0 LASTPIN (-8875 3250) $PN 1
J 2
(-8885 3260);
DISPLAY 0.680851 (-8885 3260);
PAINT MONO (-8885 3260);
FORCEPROP 0 LASTPIN (-8575 3300) $PN 2
J 0
(-8565 3310);
DISPLAY 0.680851 (-8565 3310);
PAINT MONO (-8565 3310);
FORCEPROP 0 LASTPIN (-8575 3200) $PN 3
J 0
(-8565 3210);
DISPLAY 0.680851 (-8565 3210);
PAINT MONO (-8565 3210);
FORCEPROP 1 LAST PACK_TYPE TH2
J 2
(-8650 3400);
DISPLAY 0.872340 (-8650 3400);
FORCEPROP 1 LAST CDS_LMAN_SYM_OUTLINE -150,100,50,-100
J 0
(-8675 3250);
DISPLAY 0.468085 (-8675 3250);
PAINT GREEN (-8675 3250);
DISPLAY INVISIBLE (-8675 3250);
FORCEPROP 2 LAST CDS_LIB pure_quanta
J 0
(-8675 3250);
DISPLAY INVISIBLE (-8675 3250);
FORCEPROP 1 LAST MATERIAL EMPTY
J 2
(-8675 3400);
DISPLAY 0.872340 (-8675 3400);
PAINT PINK (-8675 3400);
DISPLAY INVISIBLE (-8675 3400);
FORCEPROP 1 LAST PATH I8
J 2
(-8375 3400);
DISPLAY 0.872340 (-8375 3400);
PAINT PINK (-8375 3400);
DISPLAY INVISIBLE (-8375 3400);
FORCEPROP 1 LAST PART_NUMBER N_A
J 1
(-8615 3100);
DISPLAY 0.872340 (-8615 3100);
PAINT PINK (-8615 3100);
DISPLAY INVISIBLE (-8615 3100);
FORCEADD UNIVERSAL_GND..1
(-475 3300);
FORCEPROP 3 LASTPIN (-475 3350) SIG_NAME T1_GND\g
J 0
(-465 3360);
DISPLAY 0.659574 (-465 3360);
PAINT MONO (-465 3360);
DISPLAY INVISIBLE (-465 3360);
FORCEPROP 1 LAST HDL_POWER T1_GND
J 1
(-450 3225);
DISPLAY 0.872340 (-450 3225);
PAINT GREEN (-450 3225);
FORCEPROP 2 LAST CDS_LIB pure_quanta_power
J 0
(-475 3300);
DISPLAY INVISIBLE (-475 3300);
FORCEPROP 1 LAST PATH I80
J 0
(-400 3300);
DISPLAY 0.872340 (-400 3300);
PAINT AQUA (-400 3300);
DISPLAY INVISIBLE (-400 3300);
FORCEADD UNIVERSAL_GND..1
(-475 4075);
FORCEPROP 3 LASTPIN (-475 4125) SIG_NAME T1_GND\g
J 0
(-465 4135);
DISPLAY 0.659574 (-465 4135);
PAINT MONO (-465 4135);
DISPLAY INVISIBLE (-465 4135);
FORCEPROP 1 LAST HDL_POWER T1_GND
J 1
(-450 4000);
DISPLAY 0.872340 (-450 4000);
PAINT GREEN (-450 4000);
FORCEPROP 2 LAST CDS_LIB pure_quanta_power
J 0
(-475 4075);
DISPLAY INVISIBLE (-475 4075);
FORCEPROP 1 LAST PATH I81
J 0
(-400 4075);
DISPLAY 0.872340 (-400 4075);
PAINT AQUA (-400 4075);
DISPLAY INVISIBLE (-400 4075);
FORCEADD TP_TDR_4P_FTS..1
R 4
(-3700 5050);
FORCEPROP 1 LAST LOCATION X8
J 0
(-3825 5345);
DISPLAY 0.723404 (-3825 5345);
PAINT GREEN (-3825 5345);
FORCEPROP 0 LAST $SEC 1
J 0
(-3825 5475);
DISPLAY 0.680851 (-3825 5475);
PAINT MONO (-3825 5475);
DISPLAY INVISIBLE (-3825 5475);
FORCEPROP 0 LAST CDS_SEC 1
J 0
(-3825 5475);
DISPLAY 1.021277 (-3825 5475);
DISPLAY INVISIBLE (-3825 5475);
FORCEPROP 0 LASTPIN (-3425 4975) $PN 2
J 0
(-3415 4985);
DISPLAY 0.680851 (-3415 4985);
PAINT MONO (-3415 4985);
FORCEPROP 0 LASTPIN (-3425 5125) $PN 3
J 0
(-3415 5135);
DISPLAY 0.680851 (-3415 5135);
PAINT MONO (-3415 5135);
FORCEPROP 0 LASTPIN (-3975 4975) $PN 1
J 2
(-3985 4985);
DISPLAY 0.680851 (-3985 4985);
PAINT MONO (-3985 4985);
FORCEPROP 0 LASTPIN (-3975 5125) $PN 4
J 2
(-3985 5135);
DISPLAY 0.680851 (-3985 5135);
PAINT MONO (-3985 5135);
FORCEPROP 2 LAST VALUE TP_TDR_4P_DIP
J 0
(-3825 5250);
DISPLAY 1.021277 (-3825 5250);
FORCEPROP 2 LAST PACK_TYPE TH
J 0
(-3825 5300);
DISPLAY 1.021277 (-3825 5300);
FORCEPROP 1 LAST MATERIAL EMPTY
J 0
(-3825 5440);
DISPLAY 0.723404 (-3825 5440);
PAINT GREEN (-3825 5440);
FORCEPROP 1 LAST NEEDS_NO_SIZE TRUE
R 2
J 0
(-3700 5050);
DISPLAY 0.468085 (-3700 5050);
PAINT GREEN (-3700 5050);
DISPLAY INVISIBLE (-3700 5050);
FORCEPROP 2 LAST CDS_LIB pure_quanta
R 2
J 0
(-3700 5050);
DISPLAY INVISIBLE (-3700 5050);
FORCEPROP 1 LAST PATH I82
R 2
J 0
(-3800 4870);
DISPLAY 0.723404 (-3800 4870);
PAINT GREEN (-3800 4870);
DISPLAY INVISIBLE (-3800 4870);
FORCEPROP 1 LAST PART_NUMBER TP15
J 0
(-3825 5390);
DISPLAY 0.723404 (-3825 5390);
PAINT GREEN (-3825 5390);
DISPLAY INVISIBLE (-3825 5390);
FORCEADD UNIVERSAL_GND..1
(-3300 4825);
FORCEPROP 3 LASTPIN (-3300 4875) SIG_NAME T1_GND\g
J 0
(-3290 4885);
DISPLAY 0.659574 (-3290 4885);
PAINT MONO (-3290 4885);
DISPLAY INVISIBLE (-3290 4885);
FORCEPROP 1 LAST HDL_POWER T1_GND
J 1
(-3275 4750);
DISPLAY 0.872340 (-3275 4750);
PAINT GREEN (-3275 4750);
FORCEPROP 2 LAST CDS_LIB pure_quanta_power
J 0
(-3300 4825);
DISPLAY INVISIBLE (-3300 4825);
FORCEPROP 1 LAST PATH I83
J 0
(-3225 4825);
DISPLAY 0.872340 (-3225 4825);
PAINT AQUA (-3225 4825);
DISPLAY INVISIBLE (-3225 4825);
FORCEADD TP_TDR_4P_FTS..1
R 4
(-3700 5825);
FORCEPROP 1 LAST LOCATION X7
J 0
(-3825 6120);
DISPLAY 0.723404 (-3825 6120);
PAINT GREEN (-3825 6120);
FORCEPROP 0 LAST $SEC 1
J 0
(-3825 6250);
DISPLAY 0.680851 (-3825 6250);
PAINT MONO (-3825 6250);
DISPLAY INVISIBLE (-3825 6250);
FORCEPROP 0 LAST CDS_SEC 1
J 0
(-3825 6250);
DISPLAY 1.021277 (-3825 6250);
DISPLAY INVISIBLE (-3825 6250);
FORCEPROP 0 LASTPIN (-3425 5750) $PN 2
J 0
(-3415 5760);
DISPLAY 0.680851 (-3415 5760);
PAINT MONO (-3415 5760);
FORCEPROP 0 LASTPIN (-3425 5900) $PN 3
J 0
(-3415 5910);
DISPLAY 0.680851 (-3415 5910);
PAINT MONO (-3415 5910);
FORCEPROP 0 LASTPIN (-3975 5750) $PN 1
J 2
(-3985 5760);
DISPLAY 0.680851 (-3985 5760);
PAINT MONO (-3985 5760);
FORCEPROP 0 LASTPIN (-3975 5900) $PN 4
J 2
(-3985 5910);
DISPLAY 0.680851 (-3985 5910);
PAINT MONO (-3985 5910);
FORCEPROP 2 LAST VALUE TP_TDR_4P_DIP
J 0
(-3825 6025);
DISPLAY 1.021277 (-3825 6025);
FORCEPROP 2 LAST PACK_TYPE TH
J 0
(-3825 6075);
DISPLAY 1.021277 (-3825 6075);
FORCEPROP 1 LAST MATERIAL EMPTY
J 0
(-3825 6215);
DISPLAY 0.723404 (-3825 6215);
PAINT GREEN (-3825 6215);
FORCEPROP 1 LAST NEEDS_NO_SIZE TRUE
R 2
J 0
(-3700 5825);
DISPLAY 0.468085 (-3700 5825);
PAINT GREEN (-3700 5825);
DISPLAY INVISIBLE (-3700 5825);
FORCEPROP 2 LAST CDS_LIB pure_quanta
R 2
J 0
(-3700 5825);
DISPLAY INVISIBLE (-3700 5825);
FORCEPROP 1 LAST PATH I84
R 2
J 0
(-3800 5645);
DISPLAY 0.723404 (-3800 5645);
PAINT GREEN (-3800 5645);
DISPLAY INVISIBLE (-3800 5645);
FORCEPROP 1 LAST PART_NUMBER TP15
J 0
(-3825 6165);
DISPLAY 0.723404 (-3825 6165);
PAINT GREEN (-3825 6165);
DISPLAY INVISIBLE (-3825 6165);
FORCEADD UNIVERSAL_GND..1
(-3300 5600);
FORCEPROP 3 LASTPIN (-3300 5650) SIG_NAME T1_GND\g
J 0
(-3290 5660);
DISPLAY 0.659574 (-3290 5660);
PAINT MONO (-3290 5660);
DISPLAY INVISIBLE (-3290 5660);
FORCEPROP 1 LAST HDL_POWER T1_GND
J 1
(-3275 5525);
DISPLAY 0.872340 (-3275 5525);
PAINT GREEN (-3275 5525);
FORCEPROP 2 LAST CDS_LIB pure_quanta_power
J 0
(-3300 5600);
DISPLAY INVISIBLE (-3300 5600);
FORCEPROP 1 LAST PATH I85
J 0
(-3225 5600);
DISPLAY 0.872340 (-3225 5600);
PAINT AQUA (-3225 5600);
DISPLAY INVISIBLE (-3225 5600);
FORCEADD UNIVERSAL_GND..1
(-2625 4850);
FORCEPROP 3 LASTPIN (-2625 4900) SIG_NAME T1_GND\g
J 0
(-2615 4910);
DISPLAY 0.659574 (-2615 4910);
PAINT MONO (-2615 4910);
DISPLAY INVISIBLE (-2615 4910);
FORCEPROP 1 LAST HDL_POWER T1_GND
J 1
(-2600 4775);
DISPLAY 0.872340 (-2600 4775);
PAINT GREEN (-2600 4775);
FORCEPROP 2 LAST CDS_LIB pure_quanta_power
J 0
(-2625 4850);
DISPLAY INVISIBLE (-2625 4850);
FORCEPROP 1 LAST PATH I86
J 0
(-2550 4850);
DISPLAY 0.872340 (-2550 4850);
PAINT AQUA (-2550 4850);
DISPLAY INVISIBLE (-2550 4850);
FORCEADD TP_TDR_4P_FTS..1
(-2200 5075);
FORCEPROP 1 LAST LOCATION X8002
J 0
(-2325 5355);
DISPLAY 0.723404 (-2325 5355);
PAINT GREEN (-2325 5355);
FORCEPROP 0 LAST $SEC 1
J 0
(-2325 5500);
DISPLAY 0.680851 (-2325 5500);
PAINT MONO (-2325 5500);
DISPLAY INVISIBLE (-2325 5500);
FORCEPROP 0 LAST CDS_SEC 1
J 0
(-2325 5500);
DISPLAY 1.021277 (-2325 5500);
DISPLAY INVISIBLE (-2325 5500);
FORCEPROP 0 LASTPIN (-2475 5150) $PN 2
J 2
(-2485 5160);
DISPLAY 0.680851 (-2485 5160);
PAINT MONO (-2485 5160);
FORCEPROP 0 LASTPIN (-2475 5000) $PN 3
J 2
(-2485 5010);
DISPLAY 0.680851 (-2485 5010);
PAINT MONO (-2485 5010);
FORCEPROP 0 LASTPIN (-1925 5150) $PN 1
J 0
(-1915 5160);
DISPLAY 0.680851 (-1915 5160);
PAINT MONO (-1915 5160);
FORCEPROP 0 LASTPIN (-1925 5000) $PN 4
J 0
(-1915 5010);
DISPLAY 0.680851 (-1915 5010);
PAINT MONO (-1915 5010);
FORCEPROP 2 LAST VALUE TP_TDR_4P_DIP
J 0
(-2325 5450);
DISPLAY 1.021277 (-2325 5450);
FORCEPROP 2 LAST PACK_TYPE TH
J 0
(-2325 5400);
DISPLAY 1.021277 (-2325 5400);
FORCEPROP 1 LAST MATERIAL EMPTY
J 0
(-2325 5260);
DISPLAY 0.723404 (-2325 5260);
PAINT GREEN (-2325 5260);
FORCEPROP 1 LAST NEEDS_NO_SIZE TRUE
J 0
(-2200 5075);
DISPLAY 0.468085 (-2200 5075);
PAINT GREEN (-2200 5075);
DISPLAY INVISIBLE (-2200 5075);
FORCEPROP 2 LAST CDS_LIB pure_quanta
J 0
(-2200 5075);
DISPLAY INVISIBLE (-2200 5075);
FORCEPROP 1 LAST PATH I87
J 0
(-2100 5255);
DISPLAY 0.723404 (-2100 5255);
PAINT GREEN (-2100 5255);
DISPLAY INVISIBLE (-2100 5255);
FORCEPROP 1 LAST PART_NUMBER TP15
J 0
(-2325 5310);
DISPLAY 0.723404 (-2325 5310);
PAINT GREEN (-2325 5310);
DISPLAY INVISIBLE (-2325 5310);
FORCEADD UNIVERSAL_GND..1
(-2625 5625);
FORCEPROP 3 LASTPIN (-2625 5675) SIG_NAME T1_GND\g
J 0
(-2615 5685);
DISPLAY 0.659574 (-2615 5685);
PAINT MONO (-2615 5685);
DISPLAY INVISIBLE (-2615 5685);
FORCEPROP 1 LAST HDL_POWER T1_GND
J 1
(-2600 5550);
DISPLAY 0.872340 (-2600 5550);
PAINT GREEN (-2600 5550);
FORCEPROP 2 LAST CDS_LIB pure_quanta_power
J 0
(-2625 5625);
DISPLAY INVISIBLE (-2625 5625);
FORCEPROP 1 LAST PATH I88
J 0
(-2550 5625);
DISPLAY 0.872340 (-2550 5625);
PAINT AQUA (-2550 5625);
DISPLAY INVISIBLE (-2550 5625);
FORCEADD TP_TDR_4P_FTS..1
(-2200 5850);
FORCEPROP 1 LAST LOCATION X8001
J 0
(-2325 6130);
DISPLAY 0.723404 (-2325 6130);
PAINT GREEN (-2325 6130);
FORCEPROP 0 LAST $SEC 1
J 0
(-2325 6275);
DISPLAY 0.680851 (-2325 6275);
PAINT MONO (-2325 6275);
DISPLAY INVISIBLE (-2325 6275);
FORCEPROP 0 LAST CDS_SEC 1
J 0
(-2325 6275);
DISPLAY 1.021277 (-2325 6275);
DISPLAY INVISIBLE (-2325 6275);
FORCEPROP 0 LASTPIN (-2475 5925) $PN 2
J 2
(-2485 5935);
DISPLAY 0.680851 (-2485 5935);
PAINT MONO (-2485 5935);
FORCEPROP 0 LASTPIN (-2475 5775) $PN 3
J 2
(-2485 5785);
DISPLAY 0.680851 (-2485 5785);
PAINT MONO (-2485 5785);
FORCEPROP 0 LASTPIN (-1925 5925) $PN 1
J 0
(-1915 5935);
DISPLAY 0.680851 (-1915 5935);
PAINT MONO (-1915 5935);
FORCEPROP 0 LASTPIN (-1925 5775) $PN 4
J 0
(-1915 5785);
DISPLAY 0.680851 (-1915 5785);
PAINT MONO (-1915 5785);
FORCEPROP 1 LAST MATERIAL EMPTY
J 0
(-2325 6035);
DISPLAY 0.723404 (-2325 6035);
PAINT GREEN (-2325 6035);
FORCEPROP 2 LAST PACK_TYPE TH
J 0
(-2325 6175);
DISPLAY 1.021277 (-2325 6175);
FORCEPROP 2 LAST VALUE TP_TDR_4P_DIP
J 0
(-2325 6225);
DISPLAY 1.021277 (-2325 6225);
FORCEPROP 1 LAST NEEDS_NO_SIZE TRUE
J 0
(-2200 5850);
DISPLAY 0.468085 (-2200 5850);
PAINT GREEN (-2200 5850);
DISPLAY INVISIBLE (-2200 5850);
FORCEPROP 2 LAST CDS_LIB pure_quanta
J 0
(-2200 5850);
DISPLAY INVISIBLE (-2200 5850);
FORCEPROP 1 LAST PATH I89
J 0
(-2100 6030);
DISPLAY 0.723404 (-2100 6030);
PAINT GREEN (-2100 6030);
DISPLAY INVISIBLE (-2100 6030);
FORCEPROP 1 LAST PART_NUMBER TP15
J 0
(-2325 6085);
DISPLAY 0.723404 (-2325 6085);
PAINT GREEN (-2325 6085);
DISPLAY INVISIBLE (-2325 6085);
FORCEADD TDR_3P..2
(-8650 3775);
FORCEPROP 1 LAST LOCATION DB5
J 2
(-8625 3975);
DISPLAY 0.872340 (-8625 3975);
PAINT PINK (-8625 3975);
FORCEPROP 0 LAST $SEC 1
J 0
(-8625 4025);
DISPLAY 0.680851 (-8625 4025);
PAINT MONO (-8625 4025);
DISPLAY INVISIBLE (-8625 4025);
FORCEPROP 0 LAST CDS_SEC 1
J 0
(-8625 4025);
DISPLAY 1.021277 (-8625 4025);
DISPLAY INVISIBLE (-8625 4025);
FORCEPROP 0 LASTPIN (-8850 3775) $PN 1
J 2
(-8860 3785);
DISPLAY 0.680851 (-8860 3785);
PAINT MONO (-8860 3785);
FORCEPROP 0 LASTPIN (-8550 3825) $PN 2
J 0
(-8540 3835);
DISPLAY 0.680851 (-8540 3835);
PAINT MONO (-8540 3835);
FORCEPROP 0 LASTPIN (-8550 3725) $PN 3
J 0
(-8540 3735);
DISPLAY 0.680851 (-8540 3735);
PAINT MONO (-8540 3735);
FORCEPROP 1 LAST PACK_TYPE TH2
J 2
(-8625 3925);
DISPLAY 0.872340 (-8625 3925);
FORCEPROP 1 LAST MATERIAL EMPTY
J 2
(-8650 3925);
DISPLAY 0.872340 (-8650 3925);
PAINT PINK (-8650 3925);
DISPLAY INVISIBLE (-8650 3925);
FORCEPROP 2 LAST CDS_LIB pure_quanta
J 0
(-8650 3775);
DISPLAY INVISIBLE (-8650 3775);
FORCEPROP 1 LAST CDS_LMAN_SYM_OUTLINE -150,100,50,-100
J 0
(-8650 3775);
DISPLAY 0.468085 (-8650 3775);
PAINT GREEN (-8650 3775);
DISPLAY INVISIBLE (-8650 3775);
FORCEPROP 1 LAST PATH I9
J 2
(-8350 3925);
DISPLAY 0.872340 (-8350 3925);
PAINT PINK (-8350 3925);
DISPLAY INVISIBLE (-8350 3925);
FORCEPROP 1 LAST PART_NUMBER N_A
J 1
(-8590 3625);
DISPLAY 0.872340 (-8590 3625);
PAINT PINK (-8590 3625);
DISPLAY INVISIBLE (-8590 3625);
FORCEADD TP_TDR_4P_FTS..1
R 4
(-875 5075);
FORCEPROP 1 LAST LOCATION X8008
J 0
(-1000 5370);
DISPLAY 0.723404 (-1000 5370);
PAINT GREEN (-1000 5370);
FORCEPROP 0 LAST $SEC 1
J 0
(-1000 5500);
DISPLAY 0.680851 (-1000 5500);
PAINT MONO (-1000 5500);
DISPLAY INVISIBLE (-1000 5500);
FORCEPROP 0 LAST CDS_SEC 1
J 0
(-1000 5500);
DISPLAY 1.021277 (-1000 5500);
DISPLAY INVISIBLE (-1000 5500);
FORCEPROP 0 LASTPIN (-600 5000) $PN 2
J 0
(-590 5010);
DISPLAY 0.680851 (-590 5010);
PAINT MONO (-590 5010);
FORCEPROP 0 LASTPIN (-600 5150) $PN 3
J 0
(-590 5160);
DISPLAY 0.680851 (-590 5160);
PAINT MONO (-590 5160);
FORCEPROP 0 LASTPIN (-1150 5000) $PN 1
J 2
(-1160 5010);
DISPLAY 0.680851 (-1160 5010);
PAINT MONO (-1160 5010);
FORCEPROP 0 LASTPIN (-1150 5150) $PN 4
J 2
(-1160 5160);
DISPLAY 0.680851 (-1160 5160);
PAINT MONO (-1160 5160);
FORCEPROP 2 LAST PACK_TYPE TH
J 0
(-1000 5325);
DISPLAY 1.021277 (-1000 5325);
FORCEPROP 2 LAST VALUE TP_TDR_4P_DIP
J 0
(-1000 5275);
DISPLAY 1.021277 (-1000 5275);
FORCEPROP 1 LAST MATERIAL EMPTY
J 0
(-1000 5465);
DISPLAY 0.723404 (-1000 5465);
PAINT GREEN (-1000 5465);
FORCEPROP 1 LAST NEEDS_NO_SIZE TRUE
R 2
J 0
(-875 5075);
DISPLAY 0.468085 (-875 5075);
PAINT GREEN (-875 5075);
DISPLAY INVISIBLE (-875 5075);
FORCEPROP 2 LAST CDS_LIB pure_quanta
R 2
J 0
(-875 5075);
DISPLAY INVISIBLE (-875 5075);
FORCEPROP 1 LAST PATH I90
R 2
J 0
(-975 4895);
DISPLAY 0.723404 (-975 4895);
PAINT GREEN (-975 4895);
DISPLAY INVISIBLE (-975 4895);
FORCEPROP 1 LAST PART_NUMBER TP15
J 0
(-1000 5415);
DISPLAY 0.723404 (-1000 5415);
PAINT GREEN (-1000 5415);
DISPLAY INVISIBLE (-1000 5415);
FORCEADD UNIVERSAL_GND..1
(-475 4850);
FORCEPROP 3 LASTPIN (-475 4900) SIG_NAME T1_GND\g
J 0
(-465 4910);
DISPLAY 0.659574 (-465 4910);
PAINT MONO (-465 4910);
DISPLAY INVISIBLE (-465 4910);
FORCEPROP 1 LAST HDL_POWER T1_GND
J 1
(-450 4775);
DISPLAY 0.872340 (-450 4775);
PAINT GREEN (-450 4775);
FORCEPROP 2 LAST CDS_LIB pure_quanta_power
J 0
(-475 4850);
DISPLAY INVISIBLE (-475 4850);
FORCEPROP 1 LAST PATH I91
J 0
(-400 4850);
DISPLAY 0.872340 (-400 4850);
PAINT AQUA (-400 4850);
DISPLAY INVISIBLE (-400 4850);
FORCEADD TP_TDR_4P_FTS..1
R 4
(-875 5850);
FORCEPROP 1 LAST LOCATION X8007
J 0
(-1000 6145);
DISPLAY 0.723404 (-1000 6145);
PAINT GREEN (-1000 6145);
FORCEPROP 0 LAST $SEC 1
J 0
(-1000 6275);
DISPLAY 0.680851 (-1000 6275);
PAINT MONO (-1000 6275);
DISPLAY INVISIBLE (-1000 6275);
FORCEPROP 0 LAST CDS_SEC 1
J 0
(-1000 6275);
DISPLAY 1.021277 (-1000 6275);
DISPLAY INVISIBLE (-1000 6275);
FORCEPROP 0 LASTPIN (-600 5775) $PN 2
J 0
(-590 5785);
DISPLAY 0.680851 (-590 5785);
PAINT MONO (-590 5785);
FORCEPROP 0 LASTPIN (-600 5925) $PN 3
J 0
(-590 5935);
DISPLAY 0.680851 (-590 5935);
PAINT MONO (-590 5935);
FORCEPROP 0 LASTPIN (-1150 5775) $PN 1
J 2
(-1160 5785);
DISPLAY 0.680851 (-1160 5785);
PAINT MONO (-1160 5785);
FORCEPROP 0 LASTPIN (-1150 5925) $PN 4
J 2
(-1160 5935);
DISPLAY 0.680851 (-1160 5935);
PAINT MONO (-1160 5935);
FORCEPROP 2 LAST VALUE TP_TDR_4P_DIP
J 0
(-1000 6050);
DISPLAY 1.021277 (-1000 6050);
FORCEPROP 2 LAST PACK_TYPE TH
J 0
(-1000 6100);
DISPLAY 1.021277 (-1000 6100);
FORCEPROP 1 LAST MATERIAL EMPTY
J 0
(-1000 6240);
DISPLAY 0.723404 (-1000 6240);
PAINT GREEN (-1000 6240);
FORCEPROP 1 LAST NEEDS_NO_SIZE TRUE
R 2
J 0
(-875 5850);
DISPLAY 0.468085 (-875 5850);
PAINT GREEN (-875 5850);
DISPLAY INVISIBLE (-875 5850);
FORCEPROP 2 LAST CDS_LIB pure_quanta
R 2
J 0
(-875 5850);
DISPLAY INVISIBLE (-875 5850);
FORCEPROP 1 LAST PATH I92
R 2
J 0
(-975 5670);
DISPLAY 0.723404 (-975 5670);
PAINT GREEN (-975 5670);
DISPLAY INVISIBLE (-975 5670);
FORCEPROP 1 LAST PART_NUMBER TP15
J 0
(-1000 6190);
DISPLAY 0.723404 (-1000 6190);
PAINT GREEN (-1000 6190);
DISPLAY INVISIBLE (-1000 6190);
FORCEADD UNIVERSAL_GND..1
(-475 5625);
FORCEPROP 3 LASTPIN (-475 5675) SIG_NAME T1_GND\g
J 0
(-465 5685);
DISPLAY 0.659574 (-465 5685);
PAINT MONO (-465 5685);
DISPLAY INVISIBLE (-465 5685);
FORCEPROP 1 LAST HDL_POWER T1_GND
J 1
(-450 5550);
DISPLAY 0.872340 (-450 5550);
PAINT GREEN (-450 5550);
FORCEPROP 2 LAST CDS_LIB pure_quanta_power
J 0
(-475 5625);
DISPLAY INVISIBLE (-475 5625);
FORCEPROP 1 LAST PATH I93
J 0
(-400 5625);
DISPLAY 0.872340 (-400 5625);
PAINT AQUA (-400 5625);
DISPLAY INVISIBLE (-400 5625);
FORCEADD TP_TDR_4P_FTS..1
R 4
(-875 650);
FORCEPROP 1 LAST LOCATION X8012
J 0
(-1000 945);
DISPLAY 0.723404 (-1000 945);
PAINT GREEN (-1000 945);
FORCEPROP 0 LAST $SEC 1
J 0
(-1000 1075);
DISPLAY 0.680851 (-1000 1075);
PAINT MONO (-1000 1075);
DISPLAY INVISIBLE (-1000 1075);
FORCEPROP 0 LAST CDS_SEC 1
J 0
(-1000 1075);
DISPLAY 1.021277 (-1000 1075);
DISPLAY INVISIBLE (-1000 1075);
FORCEPROP 0 LASTPIN (-600 575) $PN 2
J 0
(-590 585);
DISPLAY 0.680851 (-590 585);
PAINT MONO (-590 585);
FORCEPROP 0 LASTPIN (-600 725) $PN 3
J 0
(-590 735);
DISPLAY 0.680851 (-590 735);
PAINT MONO (-590 735);
FORCEPROP 0 LASTPIN (-1150 575) $PN 1
J 2
(-1160 585);
DISPLAY 0.680851 (-1160 585);
PAINT MONO (-1160 585);
FORCEPROP 0 LASTPIN (-1150 725) $PN 4
J 2
(-1160 735);
DISPLAY 0.680851 (-1160 735);
PAINT MONO (-1160 735);
FORCEPROP 2 LAST VALUE TP_TDR_4P_DIP
J 0
(-1000 850);
DISPLAY 1.021277 (-1000 850);
FORCEPROP 2 LAST PACK_TYPE TH
J 0
(-1000 900);
DISPLAY 1.021277 (-1000 900);
FORCEPROP 1 LAST MATERIAL EMPTY
J 0
(-1000 1040);
DISPLAY 0.723404 (-1000 1040);
PAINT GREEN (-1000 1040);
FORCEPROP 2 LAST CDS_LIB pure_quanta
R 2
J 0
(-875 650);
DISPLAY INVISIBLE (-875 650);
FORCEPROP 1 LAST NEEDS_NO_SIZE TRUE
R 2
J 0
(-875 650);
DISPLAY 0.468085 (-875 650);
PAINT GREEN (-875 650);
DISPLAY INVISIBLE (-875 650);
FORCEPROP 1 LAST PATH I94
R 2
J 0
(-975 470);
DISPLAY 0.723404 (-975 470);
PAINT GREEN (-975 470);
DISPLAY INVISIBLE (-975 470);
FORCEPROP 1 LAST PART_NUMBER TP15
J 0
(-1000 990);
DISPLAY 0.723404 (-1000 990);
PAINT GREEN (-1000 990);
DISPLAY INVISIBLE (-1000 990);
FORCEADD UNIVERSAL_GND..1
(-3300 2500);
FORCEPROP 3 LASTPIN (-3300 2550) SIG_NAME T1_GND\g
J 0
(-3290 2560);
DISPLAY 0.659574 (-3290 2560);
PAINT MONO (-3290 2560);
DISPLAY INVISIBLE (-3290 2560);
FORCEPROP 1 LAST HDL_POWER T1_GND
J 1
(-3275 2425);
DISPLAY 0.872340 (-3275 2425);
PAINT GREEN (-3275 2425);
FORCEPROP 2 LAST CDS_LIB pure_quanta_power
J 0
(-3300 2500);
DISPLAY INVISIBLE (-3300 2500);
FORCEPROP 1 LAST PATH I95
J 0
(-3225 2500);
DISPLAY 0.872340 (-3225 2500);
PAINT AQUA (-3225 2500);
DISPLAY INVISIBLE (-3225 2500);
FORCEADD TP_TDR_4P_FTS..1
R 4
(-3700 2725);
FORCEPROP 1 LAST LOCATION X11
J 0
(-3825 3020);
DISPLAY 0.723404 (-3825 3020);
PAINT GREEN (-3825 3020);
FORCEPROP 0 LAST $SEC 1
J 0
(-3825 3150);
DISPLAY 0.680851 (-3825 3150);
PAINT MONO (-3825 3150);
DISPLAY INVISIBLE (-3825 3150);
FORCEPROP 0 LAST CDS_SEC 1
J 0
(-3825 3150);
DISPLAY 1.021277 (-3825 3150);
DISPLAY INVISIBLE (-3825 3150);
FORCEPROP 0 LASTPIN (-3425 2650) $PN 2
J 0
(-3415 2660);
DISPLAY 0.680851 (-3415 2660);
PAINT MONO (-3415 2660);
FORCEPROP 0 LASTPIN (-3425 2800) $PN 3
J 0
(-3415 2810);
DISPLAY 0.680851 (-3415 2810);
PAINT MONO (-3415 2810);
FORCEPROP 0 LASTPIN (-3975 2650) $PN 1
J 2
(-3985 2660);
DISPLAY 0.680851 (-3985 2660);
PAINT MONO (-3985 2660);
FORCEPROP 0 LASTPIN (-3975 2800) $PN 4
J 2
(-3985 2810);
DISPLAY 0.680851 (-3985 2810);
PAINT MONO (-3985 2810);
FORCEPROP 2 LAST VALUE TP_TDR_4P_DIP
J 0
(-3825 2925);
DISPLAY 1.021277 (-3825 2925);
FORCEPROP 1 LAST MATERIAL EMPTY
J 0
(-3825 3115);
DISPLAY 0.723404 (-3825 3115);
PAINT GREEN (-3825 3115);
FORCEPROP 2 LAST PACK_TYPE TH
J 0
(-3825 2975);
DISPLAY 1.021277 (-3825 2975);
FORCEPROP 2 LAST CDS_LIB pure_quanta
R 2
J 0
(-3700 2725);
DISPLAY INVISIBLE (-3700 2725);
FORCEPROP 1 LAST NEEDS_NO_SIZE TRUE
R 2
J 0
(-3700 2725);
DISPLAY 0.468085 (-3700 2725);
PAINT GREEN (-3700 2725);
DISPLAY INVISIBLE (-3700 2725);
FORCEPROP 1 LAST PATH I96
R 2
J 0
(-3800 2545);
DISPLAY 0.723404 (-3800 2545);
PAINT GREEN (-3800 2545);
DISPLAY INVISIBLE (-3800 2545);
FORCEPROP 1 LAST PART_NUMBER TP15
J 0
(-3825 3065);
DISPLAY 0.723404 (-3825 3065);
PAINT GREEN (-3825 3065);
DISPLAY INVISIBLE (-3825 3065);
FORCEADD QUANTA_TITLE_BLOCK_C..1
(0 0);
FORCEPROP 0 LAST CDS_CON_LAST_MODIFIED Thu Sep 14 16:12:46 2023
J 0
(-1885 15);
DISPLAY INVISIBLE (-1885 15);
FORCEPROP 1 LAST CUSTOM_TXT_CDS <CON_LAST_MODIFIED>
J 0
(-1885 15);
DISPLAY 0.978723 (-1885 15);
FORCEPROP 2 LAST CUSTOM_TXT_CDS <XR_PAGE_TITLE>
J 0
(-7890 5250);
DISPLAY 0.638298 (-7890 5250);
PAINT PINK (-7890 5250);
DISPLAY INVISIBLE (-7890 5250);
FORCEPROP 1 LAST CUSTOM_TXT_CDS <NAME_2>
J 0
(-3175 50);
FORCEPROP 1 LAST CUSTOM_TXT_CDS <NAME_1>
J 0
(-3175 175);
FORCEPROP 1 LAST CUSTOM_TXT_CDS <Q_NUMBER>
J 0
(-1403 103);
DISPLAY 1.212766 (-1403 103);
FORCEPROP 1 LAST CUSTOM_TXT_CDS <Q_PROJ>
J 0
(-2382 102);
DISPLAY 1.212766 (-2382 102);
FORCEPROP 1 LAST CUSTOM_TXT_CDS <Q_REV>
J 0
(-184 103);
DISPLAY 1.212766 (-184 103);
FORCEPROP 1 LAST CUSTOM_TXT_CDS <CON_PAGE_NUM> OF <CON_TOTAL_PAGES>
J 0
(-446 18);
DISPLAY 0.978723 (-446 18);
FORCEPROP 1 LAST Q_TITLE TDR_1
J 0
(-9366 26);
DISPLAY 2.446809 (-9366 26);
PAINT GREEN (-9366 26);
FORCEPROP 2 LAST CDS_LIB pure_quanta
J 0
(0 0);
DISPLAY INVISIBLE (0 0);
FORCEPROP 1 LAST CDS_LMAN_SYM_OUTLINE -9475,6775,100,-125
J 0
(0 0);
DISPLAY 0.468085 (0 0);
PAINT GREEN (0 0);
DISPLAY INVISIBLE (0 0);
FORCEPROP 2 LAST PAGE_BORDER TRUE
J 0
(-7890 5250);
DISPLAY 0.638298 (-7890 5250);
PAINT PINK (-7890 5250);
DISPLAY INVISIBLE (-7890 5250);
FORCEPROP 2 LAST CDS_XR_PAGE_TITLE CR-261 : @T6G_MB_LIB.T6G(SCH_1):PAGE261
J 0
(-7890 5250);
DISPLAY 0.638298 (-7890 5250);
PAINT PINK (-7890 5250);
DISPLAY INVISIBLE (-7890 5250);
FORCEPROP 1 LAST Q_DEPT BU9
J 1
(-3763 49);
DISPLAY 1.957447 (-3763 49);
PAINT GREEN (-3763 49);
DISPLAY INVISIBLE (-3763 49);
FORCEPROP 1 LAST COMMENT_BODY TRUE
J 0
(12 -13);
DISPLAY 0.978723 (12 -13);
PAINT GREEN (12 -13);
DISPLAY INVISIBLE (12 -13);
WIRE 16 -1 (-1150 5775)(-1925 5775);
FORCEPROP 0 LAST CDS_PHYS_NET_NAME TDR_DIFF_85_TOP_DN
J 0
(-1885 5815);
PAINT MONO (-1885 5815);
DISPLAY INVISIBLE (-1885 5815);
FORCEPROP 2 LAST SIG_NAME TDR_DIFF_85_TOP_DN
J 0
(-1810 5785);
DISPLAY 0.638298 (-1810 5785);
PAINT WHITE (-1810 5785);
FORCEPROP 2 LASTPROP $XRERR UNIQUE?
J 0
(-2050 5785);
DISPLAY 0.638298 (-2050 5785);
PAINT MONO (-2050 5785);
DISPLAY INVISIBLE (-2050 5785);
WIRE 16 -1 (-1150 5925)(-1925 5925);
FORCEPROP 0 LAST CDS_PHYS_NET_NAME TDR_DIFF_85_TOP_DP
J 0
(-1885 5965);
PAINT MONO (-1885 5965);
DISPLAY INVISIBLE (-1885 5965);
FORCEPROP 2 LAST SIG_NAME TDR_DIFF_85_TOP_DP
J 0
(-1810 5935);
DISPLAY 0.638298 (-1810 5935);
PAINT WHITE (-1810 5935);
FORCEPROP 2 LASTPROP $XRERR UNIQUE?
J 0
(-2050 5935);
DISPLAY 0.638298 (-2050 5935);
PAINT MONO (-2050 5935);
DISPLAY INVISIBLE (-2050 5935);
WIRE 16 -1 (-1150 5000)(-1925 5000);
FORCEPROP 0 LAST CDS_PHYS_NET_NAME TDR_DIFF_85_IN1_DN
J 0
(-1885 5040);
PAINT MONO (-1885 5040);
DISPLAY INVISIBLE (-1885 5040);
FORCEPROP 2 LAST SIG_NAME TDR_DIFF_85_IN1_DN
J 0
(-1810 5010);
DISPLAY 0.638298 (-1810 5010);
PAINT WHITE (-1810 5010);
FORCEPROP 2 LASTPROP $XRERR UNIQUE?
J 0
(-2050 5010);
DISPLAY 0.638298 (-2050 5010);
PAINT MONO (-2050 5010);
DISPLAY INVISIBLE (-2050 5010);
WIRE 16 -1 (-1150 5150)(-1925 5150);
FORCEPROP 0 LAST CDS_PHYS_NET_NAME TDR_DIFF_85_IN1_DP
J 0
(-1885 5190);
PAINT MONO (-1885 5190);
DISPLAY INVISIBLE (-1885 5190);
FORCEPROP 2 LAST SIG_NAME TDR_DIFF_85_IN1_DP
J 0
(-1810 5160);
DISPLAY 0.638298 (-1810 5160);
PAINT WHITE (-1810 5160);
FORCEPROP 2 LASTPROP $XRERR UNIQUE?
J 0
(-2050 5160);
DISPLAY 0.638298 (-2050 5160);
PAINT MONO (-2050 5160);
DISPLAY INVISIBLE (-2050 5160);
WIRE 16 -1 (-1150 4225)(-1925 4225);
FORCEPROP 0 LAST CDS_PHYS_NET_NAME TDR_DIFF_85_IN2_DN
J 0
(-1885 4265);
PAINT MONO (-1885 4265);
DISPLAY INVISIBLE (-1885 4265);
FORCEPROP 2 LAST SIG_NAME TDR_DIFF_85_IN2_DN
J 0
(-1810 4235);
DISPLAY 0.638298 (-1810 4235);
PAINT WHITE (-1810 4235);
FORCEPROP 2 LASTPROP $XRERR UNIQUE?
J 0
(-2050 4235);
DISPLAY 0.638298 (-2050 4235);
PAINT MONO (-2050 4235);
DISPLAY INVISIBLE (-2050 4235);
WIRE 16 -1 (-1150 4375)(-1925 4375);
FORCEPROP 0 LAST CDS_PHYS_NET_NAME TDR_DIFF_85_IN2_DP
J 0
(-1885 4415);
PAINT MONO (-1885 4415);
DISPLAY INVISIBLE (-1885 4415);
FORCEPROP 2 LAST SIG_NAME TDR_DIFF_85_IN2_DP
J 0
(-1810 4385);
DISPLAY 0.638298 (-1810 4385);
PAINT WHITE (-1810 4385);
FORCEPROP 2 LASTPROP $XRERR UNIQUE?
J 0
(-2050 4385);
DISPLAY 0.638298 (-2050 4385);
PAINT MONO (-2050 4385);
DISPLAY INVISIBLE (-2050 4385);
WIRE 16 -1 (-1150 2825)(-1925 2825);
FORCEPROP 0 LAST CDS_PHYS_NET_NAME TDR_DIFF_85_IN4_DP
J 0
(-1885 2865);
PAINT MONO (-1885 2865);
DISPLAY INVISIBLE (-1885 2865);
FORCEPROP 2 LAST SIG_NAME TDR_DIFF_85_IN4_DP
J 0
(-1810 2835);
DISPLAY 0.638298 (-1810 2835);
PAINT WHITE (-1810 2835);
FORCEPROP 2 LASTPROP $XRERR UNIQUE?
J 0
(-2050 2835);
DISPLAY 0.638298 (-2050 2835);
PAINT MONO (-2050 2835);
DISPLAY INVISIBLE (-2050 2835);
WIRE 16 -1 (-1150 2675)(-1925 2675);
FORCEPROP 0 LAST CDS_PHYS_NET_NAME TDR_DIFF_85_IN4_DN
J 0
(-1885 2715);
PAINT MONO (-1885 2715);
DISPLAY INVISIBLE (-1885 2715);
FORCEPROP 2 LAST SIG_NAME TDR_DIFF_85_IN4_DN
J 0
(-1810 2685);
DISPLAY 0.638298 (-1810 2685);
PAINT WHITE (-1810 2685);
FORCEPROP 2 LASTPROP $XRERR UNIQUE?
J 0
(-2050 2685);
DISPLAY 0.638298 (-2050 2685);
PAINT MONO (-2050 2685);
DISPLAY INVISIBLE (-2050 2685);
WIRE 16 -1 (-1150 2150)(-1925 2150);
FORCEPROP 0 LAST CDS_PHYS_NET_NAME TDR_DIFF_85_IN5_DP
J 0
(-1885 2190);
PAINT MONO (-1885 2190);
DISPLAY INVISIBLE (-1885 2190);
FORCEPROP 2 LAST SIG_NAME TDR_DIFF_85_IN5_DP
J 0
(-1810 2160);
DISPLAY 0.638298 (-1810 2160);
PAINT WHITE (-1810 2160);
FORCEPROP 2 LASTPROP $XRERR UNIQUE?
J 0
(-2050 2160);
DISPLAY 0.638298 (-2050 2160);
PAINT MONO (-2050 2160);
DISPLAY INVISIBLE (-2050 2160);
WIRE 16 -1 (-1150 3450)(-1925 3450);
FORCEPROP 0 LAST CDS_PHYS_NET_NAME TDR_DIFF_85_IN3_DN
J 0
(-1885 3490);
PAINT MONO (-1885 3490);
DISPLAY INVISIBLE (-1885 3490);
FORCEPROP 2 LAST SIG_NAME TDR_DIFF_85_IN3_DN
J 0
(-1810 3460);
DISPLAY 0.638298 (-1810 3460);
PAINT WHITE (-1810 3460);
FORCEPROP 2 LASTPROP $XRERR UNIQUE?
J 0
(-2050 3460);
DISPLAY 0.638298 (-2050 3460);
PAINT MONO (-2050 3460);
DISPLAY INVISIBLE (-2050 3460);
WIRE 16 -1 (-1150 3600)(-1925 3600);
FORCEPROP 0 LAST CDS_PHYS_NET_NAME TDR_DIFF_85_IN3_DP
J 0
(-1885 3640);
PAINT MONO (-1885 3640);
DISPLAY INVISIBLE (-1885 3640);
FORCEPROP 2 LAST SIG_NAME TDR_DIFF_85_IN3_DP
J 0
(-1810 3610);
DISPLAY 0.638298 (-1810 3610);
PAINT WHITE (-1810 3610);
FORCEPROP 2 LASTPROP $XRERR UNIQUE?
J 0
(-2050 3610);
DISPLAY 0.638298 (-2050 3610);
PAINT MONO (-2050 3610);
DISPLAY INVISIBLE (-2050 3610);
WIRE 16 -1 (-1150 2000)(-1925 2000);
FORCEPROP 0 LAST CDS_PHYS_NET_NAME TDR_DIFF_85_IN5_DN
J 0
(-1885 2040);
PAINT MONO (-1885 2040);
DISPLAY INVISIBLE (-1885 2040);
FORCEPROP 2 LAST SIG_NAME TDR_DIFF_85_IN5_DN
J 0
(-1810 2010);
DISPLAY 0.638298 (-1810 2010);
PAINT WHITE (-1810 2010);
FORCEPROP 2 LASTPROP $XRERR UNIQUE?
J 0
(-2050 2010);
DISPLAY 0.638298 (-2050 2010);
PAINT MONO (-2050 2010);
DISPLAY INVISIBLE (-2050 2010);
WIRE 16 -1 (-1150 1225)(-1925 1225);
FORCEPROP 0 LAST CDS_PHYS_NET_NAME TDR_DIFF_85_IN6_DN
J 0
(-1885 1265);
PAINT MONO (-1885 1265);
DISPLAY INVISIBLE (-1885 1265);
FORCEPROP 2 LAST SIG_NAME TDR_DIFF_85_IN6_DN
J 0
(-1810 1235);
DISPLAY 0.638298 (-1810 1235);
PAINT WHITE (-1810 1235);
FORCEPROP 2 LASTPROP $XRERR UNIQUE?
J 0
(-2050 1235);
DISPLAY 0.638298 (-2050 1235);
PAINT MONO (-2050 1235);
DISPLAY INVISIBLE (-2050 1235);
WIRE 16 -1 (-1150 1375)(-1925 1375);
FORCEPROP 0 LAST CDS_PHYS_NET_NAME TDR_DIFF_85_IN6_DP
J 0
(-1885 1415);
PAINT MONO (-1885 1415);
DISPLAY INVISIBLE (-1885 1415);
FORCEPROP 2 LAST SIG_NAME TDR_DIFF_85_IN6_DP
J 0
(-1810 1385);
DISPLAY 0.638298 (-1810 1385);
PAINT WHITE (-1810 1385);
FORCEPROP 2 LASTPROP $XRERR UNIQUE?
J 0
(-2050 1385);
DISPLAY 0.638298 (-2050 1385);
PAINT MONO (-2050 1385);
DISPLAY INVISIBLE (-2050 1385);
WIRE 16 -1 (-1150 575)(-1925 575);
FORCEPROP 0 LAST CDS_PHYS_NET_NAME TDR_DIFF_85_BOT_DN
J 0
(-1885 615);
PAINT MONO (-1885 615);
DISPLAY INVISIBLE (-1885 615);
FORCEPROP 2 LAST SIG_NAME TDR_DIFF_85_BOT_DN
J 0
(-1810 585);
DISPLAY 0.638298 (-1810 585);
PAINT WHITE (-1810 585);
FORCEPROP 2 LASTPROP $XRERR UNIQUE?
J 0
(-2050 585);
DISPLAY 0.638298 (-2050 585);
PAINT MONO (-2050 585);
DISPLAY INVISIBLE (-2050 585);
WIRE 16 -1 (-1150 725)(-1925 725);
FORCEPROP 0 LAST CDS_PHYS_NET_NAME TDR_DIFF_85_BOT_DP
J 0
(-1885 765);
PAINT MONO (-1885 765);
DISPLAY INVISIBLE (-1885 765);
FORCEPROP 2 LAST SIG_NAME TDR_DIFF_85_BOT_DP
J 0
(-1810 735);
DISPLAY 0.638298 (-1810 735);
PAINT WHITE (-1810 735);
FORCEPROP 2 LASTPROP $XRERR UNIQUE?
J 0
(-2050 735);
DISPLAY 0.638298 (-2050 735);
PAINT MONO (-2050 735);
DISPLAY INVISIBLE (-2050 735);
WIRE 16 -1 (-3975 5750)(-4750 5750);
FORCEPROP 0 LAST CDS_PHYS_NET_NAME TDR_DIFF_80_TOP_DN
J 0
(-4710 5790);
PAINT MONO (-4710 5790);
DISPLAY INVISIBLE (-4710 5790);
FORCEPROP 2 LAST SIG_NAME TDR_DIFF_80_TOP_DN
J 0
(-4635 5760);
DISPLAY 0.638298 (-4635 5760);
PAINT WHITE (-4635 5760);
FORCEPROP 2 LASTPROP $XRERR UNIQUE?
J 0
(-4875 5760);
DISPLAY 0.638298 (-4875 5760);
PAINT MONO (-4875 5760);
DISPLAY INVISIBLE (-4875 5760);
WIRE 16 -1 (-3975 5900)(-4750 5900);
FORCEPROP 0 LAST CDS_PHYS_NET_NAME TDR_DIFF_80_TOP_DP
J 0
(-4710 5940);
PAINT MONO (-4710 5940);
DISPLAY INVISIBLE (-4710 5940);
FORCEPROP 2 LAST SIG_NAME TDR_DIFF_80_TOP_DP
J 0
(-4635 5910);
DISPLAY 0.638298 (-4635 5910);
PAINT WHITE (-4635 5910);
FORCEPROP 2 LASTPROP $XRERR UNIQUE?
J 0
(-4875 5910);
DISPLAY 0.638298 (-4875 5910);
PAINT MONO (-4875 5910);
DISPLAY INVISIBLE (-4875 5910);
WIRE 16 -1 (-3975 4975)(-4750 4975);
FORCEPROP 0 LAST CDS_PHYS_NET_NAME TDR_DIFF_80_IN1_DN
J 0
(-4710 5015);
PAINT MONO (-4710 5015);
DISPLAY INVISIBLE (-4710 5015);
FORCEPROP 2 LAST SIG_NAME TDR_DIFF_80_IN1_DN
J 0
(-4635 4985);
DISPLAY 0.638298 (-4635 4985);
PAINT WHITE (-4635 4985);
FORCEPROP 2 LASTPROP $XRERR UNIQUE?
J 0
(-4875 4985);
DISPLAY 0.638298 (-4875 4985);
PAINT MONO (-4875 4985);
DISPLAY INVISIBLE (-4875 4985);
WIRE 16 -1 (-3975 5125)(-4750 5125);
FORCEPROP 0 LAST CDS_PHYS_NET_NAME TDR_DIFF_80_IN1_DP
J 0
(-4710 5165);
PAINT MONO (-4710 5165);
DISPLAY INVISIBLE (-4710 5165);
FORCEPROP 2 LAST SIG_NAME TDR_DIFF_80_IN1_DP
J 0
(-4635 5135);
DISPLAY 0.638298 (-4635 5135);
PAINT WHITE (-4635 5135);
FORCEPROP 2 LASTPROP $XRERR UNIQUE?
J 0
(-4875 5135);
DISPLAY 0.638298 (-4875 5135);
PAINT MONO (-4875 5135);
DISPLAY INVISIBLE (-4875 5135);
WIRE 16 -1 (-3975 4200)(-4750 4200);
FORCEPROP 0 LAST CDS_PHYS_NET_NAME TDR_DIFF_80_IN2_DN
J 0
(-4710 4240);
PAINT MONO (-4710 4240);
DISPLAY INVISIBLE (-4710 4240);
FORCEPROP 2 LAST SIG_NAME TDR_DIFF_80_IN2_DN
J 0
(-4635 4210);
DISPLAY 0.638298 (-4635 4210);
PAINT WHITE (-4635 4210);
FORCEPROP 2 LASTPROP $XRERR UNIQUE?
J 0
(-4875 4210);
DISPLAY 0.638298 (-4875 4210);
PAINT MONO (-4875 4210);
DISPLAY INVISIBLE (-4875 4210);
WIRE 16 -1 (-3975 4350)(-4750 4350);
FORCEPROP 0 LAST CDS_PHYS_NET_NAME TDR_DIFF_80_IN2_DP
J 0
(-4710 4390);
PAINT MONO (-4710 4390);
DISPLAY INVISIBLE (-4710 4390);
FORCEPROP 2 LAST SIG_NAME TDR_DIFF_80_IN2_DP
J 0
(-4635 4360);
DISPLAY 0.638298 (-4635 4360);
PAINT WHITE (-4635 4360);
FORCEPROP 2 LASTPROP $XRERR UNIQUE?
J 0
(-4875 4360);
DISPLAY 0.638298 (-4875 4360);
PAINT MONO (-4875 4360);
DISPLAY INVISIBLE (-4875 4360);
WIRE 16 -1 (-3975 3425)(-4750 3425);
FORCEPROP 0 LAST CDS_PHYS_NET_NAME TDR_DIFF_80_IN3_DN
J 0
(-4710 3465);
PAINT MONO (-4710 3465);
DISPLAY INVISIBLE (-4710 3465);
FORCEPROP 2 LAST SIG_NAME TDR_DIFF_80_IN3_DN
J 0
(-4635 3435);
DISPLAY 0.638298 (-4635 3435);
PAINT WHITE (-4635 3435);
FORCEPROP 2 LASTPROP $XRERR UNIQUE?
J 0
(-4875 3435);
DISPLAY 0.638298 (-4875 3435);
PAINT MONO (-4875 3435);
DISPLAY INVISIBLE (-4875 3435);
WIRE 16 -1 (-3975 3575)(-4750 3575);
FORCEPROP 0 LAST CDS_PHYS_NET_NAME TDR_DIFF_80_IN3_DP
J 0
(-4710 3615);
PAINT MONO (-4710 3615);
DISPLAY INVISIBLE (-4710 3615);
FORCEPROP 2 LAST SIG_NAME TDR_DIFF_80_IN3_DP
J 0
(-4635 3585);
DISPLAY 0.638298 (-4635 3585);
PAINT WHITE (-4635 3585);
FORCEPROP 2 LASTPROP $XRERR UNIQUE?
J 0
(-4875 3585);
DISPLAY 0.638298 (-4875 3585);
PAINT MONO (-4875 3585);
DISPLAY INVISIBLE (-4875 3585);
WIRE 16 -1 (-3975 2650)(-4750 2650);
FORCEPROP 0 LAST CDS_PHYS_NET_NAME TDR_DIFF_80_IN4_DN
J 0
(-4710 2690);
PAINT MONO (-4710 2690);
DISPLAY INVISIBLE (-4710 2690);
FORCEPROP 2 LAST SIG_NAME TDR_DIFF_80_IN4_DN
J 0
(-4635 2660);
DISPLAY 0.638298 (-4635 2660);
PAINT WHITE (-4635 2660);
FORCEPROP 2 LASTPROP $XRERR UNIQUE?
J 0
(-4875 2660);
DISPLAY 0.638298 (-4875 2660);
PAINT MONO (-4875 2660);
DISPLAY INVISIBLE (-4875 2660);
WIRE 16 -1 (-3975 2800)(-4750 2800);
FORCEPROP 0 LAST CDS_PHYS_NET_NAME TDR_DIFF_80_IN4_DP
J 0
(-4710 2840);
PAINT MONO (-4710 2840);
DISPLAY INVISIBLE (-4710 2840);
FORCEPROP 2 LAST SIG_NAME TDR_DIFF_80_IN4_DP
J 0
(-4635 2810);
DISPLAY 0.638298 (-4635 2810);
PAINT WHITE (-4635 2810);
FORCEPROP 2 LASTPROP $XRERR UNIQUE?
J 0
(-4875 2810);
DISPLAY 0.638298 (-4875 2810);
PAINT MONO (-4875 2810);
DISPLAY INVISIBLE (-4875 2810);
WIRE 16 -1 (-3975 1975)(-4750 1975);
FORCEPROP 0 LAST CDS_PHYS_NET_NAME TDR_DIFF_80_IN5_DN
J 0
(-4710 2015);
PAINT MONO (-4710 2015);
DISPLAY INVISIBLE (-4710 2015);
FORCEPROP 2 LAST SIG_NAME TDR_DIFF_80_IN5_DN
J 0
(-4635 1985);
DISPLAY 0.638298 (-4635 1985);
PAINT WHITE (-4635 1985);
FORCEPROP 2 LASTPROP $XRERR UNIQUE?
J 0
(-4875 1985);
DISPLAY 0.638298 (-4875 1985);
PAINT MONO (-4875 1985);
DISPLAY INVISIBLE (-4875 1985);
WIRE 16 -1 (-3975 2125)(-4750 2125);
FORCEPROP 0 LAST CDS_PHYS_NET_NAME TDR_DIFF_80_IN5_DP
J 0
(-4710 2165);
PAINT MONO (-4710 2165);
DISPLAY INVISIBLE (-4710 2165);
FORCEPROP 2 LAST SIG_NAME TDR_DIFF_80_IN5_DP
J 0
(-4635 2135);
DISPLAY 0.638298 (-4635 2135);
PAINT WHITE (-4635 2135);
FORCEPROP 2 LASTPROP $XRERR UNIQUE?
J 0
(-4875 2135);
DISPLAY 0.638298 (-4875 2135);
PAINT MONO (-4875 2135);
DISPLAY INVISIBLE (-4875 2135);
WIRE 16 -1 (-3975 1200)(-4750 1200);
FORCEPROP 0 LAST CDS_PHYS_NET_NAME TDR_DIFF_80_IN6_DN
J 0
(-4710 1240);
PAINT MONO (-4710 1240);
DISPLAY INVISIBLE (-4710 1240);
FORCEPROP 2 LAST SIG_NAME TDR_DIFF_80_IN6_DN
J 0
(-4635 1210);
DISPLAY 0.638298 (-4635 1210);
PAINT WHITE (-4635 1210);
FORCEPROP 2 LASTPROP $XRERR UNIQUE?
J 0
(-4875 1210);
DISPLAY 0.638298 (-4875 1210);
PAINT MONO (-4875 1210);
DISPLAY INVISIBLE (-4875 1210);
WIRE 16 -1 (-3975 1350)(-4750 1350);
FORCEPROP 0 LAST CDS_PHYS_NET_NAME TDR_DIFF_80_IN6_DP
J 0
(-4710 1390);
PAINT MONO (-4710 1390);
DISPLAY INVISIBLE (-4710 1390);
FORCEPROP 2 LAST SIG_NAME TDR_DIFF_80_IN6_DP
J 0
(-4635 1360);
DISPLAY 0.638298 (-4635 1360);
PAINT WHITE (-4635 1360);
FORCEPROP 2 LASTPROP $XRERR UNIQUE?
J 0
(-4875 1360);
DISPLAY 0.638298 (-4875 1360);
PAINT MONO (-4875 1360);
DISPLAY INVISIBLE (-4875 1360);
WIRE 16 -1 (-3975 550)(-4750 550);
FORCEPROP 0 LAST CDS_PHYS_NET_NAME TDR_DIFF_80_BOT_DN
J 0
(-4710 590);
PAINT MONO (-4710 590);
DISPLAY INVISIBLE (-4710 590);
FORCEPROP 2 LAST SIG_NAME TDR_DIFF_80_BOT_DN
J 0
(-4635 560);
DISPLAY 0.638298 (-4635 560);
PAINT WHITE (-4635 560);
FORCEPROP 2 LASTPROP $XRERR UNIQUE?
J 0
(-4875 560);
DISPLAY 0.638298 (-4875 560);
PAINT MONO (-4875 560);
DISPLAY INVISIBLE (-4875 560);
WIRE 16 -1 (-3975 700)(-4750 700);
FORCEPROP 0 LAST CDS_PHYS_NET_NAME TDR_DIFF_80_BOT_DP
J 0
(-4710 740);
PAINT MONO (-4710 740);
DISPLAY INVISIBLE (-4710 740);
FORCEPROP 2 LAST SIG_NAME TDR_DIFF_80_BOT_DP
J 0
(-4635 710);
DISPLAY 0.638298 (-4635 710);
PAINT WHITE (-4635 710);
FORCEPROP 2 LASTPROP $XRERR UNIQUE?
J 0
(-4875 710);
DISPLAY 0.638298 (-4875 710);
PAINT MONO (-4875 710);
DISPLAY INVISIBLE (-4875 710);
WIRE 16 -1 (-6150 5925)(-6150 5825);
WIRE 16 -1 (-6150 5925)(-6850 5925);
FORCEPROP 0 LAST CDS_PHYS_NET_NAME TDR_SE_50_OHM_TOP
J 0
(-6810 5965);
PAINT MONO (-6810 5965);
DISPLAY INVISIBLE (-6810 5965);
FORCEPROP 2 LAST SIG_NAME TDR_SE_50_OHM_TOP
J 0
(-6735 5935);
DISPLAY 0.638298 (-6735 5935);
PAINT WHITE (-6735 5935);
FORCEPROP 2 LASTPROP $XRERR UNIQUE?
J 0
(-6975 5935);
DISPLAY 0.638298 (-6975 5935);
PAINT MONO (-6975 5935);
DISPLAY INVISIBLE (-6975 5935);
WIRE 16 -1 (-6150 5825)(-6850 5825);
WIRE 16 -1 (-6150 4875)(-6150 4775);
WIRE 16 -1 (-6150 4875)(-6850 4875);
FORCEPROP 0 LAST CDS_PHYS_NET_NAME TDR_SE_50_OHM_IN2
J 0
(-6810 4915);
PAINT MONO (-6810 4915);
DISPLAY INVISIBLE (-6810 4915);
FORCEPROP 2 LAST SIG_NAME TDR_SE_50_OHM_IN2
J 0
(-6735 4885);
DISPLAY 0.638298 (-6735 4885);
PAINT WHITE (-6735 4885);
FORCEPROP 2 LASTPROP $XRERR UNIQUE?
J 0
(-6975 4885);
DISPLAY 0.638298 (-6975 4885);
PAINT MONO (-6975 4885);
DISPLAY INVISIBLE (-6975 4885);
WIRE 16 -1 (-6150 4775)(-6850 4775);
WIRE 16 -1 (-6150 5400)(-6150 5300);
WIRE 16 -1 (-6150 5400)(-6850 5400);
FORCEPROP 0 LAST CDS_PHYS_NET_NAME TDR_SE_50_OHM_IN1
J 0
(-6810 5440);
PAINT MONO (-6810 5440);
DISPLAY INVISIBLE (-6810 5440);
FORCEPROP 2 LAST SIG_NAME TDR_SE_50_OHM_IN1
J 0
(-6735 5410);
DISPLAY 0.638298 (-6735 5410);
PAINT WHITE (-6735 5410);
FORCEPROP 2 LASTPROP $XRERR UNIQUE?
J 0
(-6975 5410);
DISPLAY 0.638298 (-6975 5410);
PAINT MONO (-6975 5410);
DISPLAY INVISIBLE (-6975 5410);
WIRE 16 -1 (-6150 5300)(-6850 5300);
WIRE 16 -1 (-6150 4350)(-6150 4250);
WIRE 16 -1 (-6150 4350)(-6850 4350);
FORCEPROP 0 LAST CDS_PHYS_NET_NAME TDR_SE_50_OHM_IN3
J 0
(-6810 4390);
PAINT MONO (-6810 4390);
DISPLAY INVISIBLE (-6810 4390);
FORCEPROP 2 LAST SIG_NAME TDR_SE_50_OHM_IN3
J 0
(-6735 4360);
DISPLAY 0.638298 (-6735 4360);
PAINT WHITE (-6735 4360);
FORCEPROP 2 LASTPROP $XRERR UNIQUE?
J 0
(-6975 4360);
DISPLAY 0.638298 (-6975 4360);
PAINT MONO (-6975 4360);
DISPLAY INVISIBLE (-6975 4360);
WIRE 16 -1 (-6150 4250)(-6850 4250);
WIRE 16 -1 (-6175 3300)(-6175 3200);
WIRE 16 -1 (-6175 3300)(-6875 3300);
FORCEPROP 0 LAST CDS_PHYS_NET_NAME TDR_SE_50_OHM_IN5
J 0
(-6835 3340);
PAINT MONO (-6835 3340);
DISPLAY INVISIBLE (-6835 3340);
FORCEPROP 2 LAST SIG_NAME TDR_SE_50_OHM_IN5
J 0
(-6760 3310);
DISPLAY 0.638298 (-6760 3310);
PAINT WHITE (-6760 3310);
FORCEPROP 2 LASTPROP $XRERR UNIQUE?
J 0
(-7000 3310);
DISPLAY 0.638298 (-7000 3310);
PAINT MONO (-7000 3310);
DISPLAY INVISIBLE (-7000 3310);
WIRE 16 -1 (-6175 3200)(-6875 3200);
WIRE 16 -1 (-6200 2225)(-6200 2125);
WIRE 16 -1 (-6200 2225)(-6900 2225);
FORCEPROP 0 LAST CDS_PHYS_NET_NAME TDR_SE_50_OHM_BOT
J 0
(-6860 2265);
PAINT MONO (-6860 2265);
DISPLAY INVISIBLE (-6860 2265);
FORCEPROP 2 LAST SIG_NAME TDR_SE_50_OHM_BOT
J 0
(-6785 2235);
DISPLAY 0.638298 (-6785 2235);
PAINT WHITE (-6785 2235);
FORCEPROP 2 LASTPROP $XRERR UNIQUE?
J 0
(-7025 2235);
DISPLAY 0.638298 (-7025 2235);
PAINT MONO (-7025 2235);
DISPLAY INVISIBLE (-7025 2235);
WIRE 16 -1 (-6200 2125)(-6900 2125);
WIRE 16 -1 (-6150 3825)(-6150 3725);
WIRE 16 -1 (-6150 3825)(-6850 3825);
FORCEPROP 0 LAST CDS_PHYS_NET_NAME TDR_SE_50_OHM_IN4
J 0
(-6810 3865);
PAINT MONO (-6810 3865);
DISPLAY INVISIBLE (-6810 3865);
FORCEPROP 2 LAST SIG_NAME TDR_SE_50_OHM_IN4
J 0
(-6735 3835);
DISPLAY 0.638298 (-6735 3835);
PAINT WHITE (-6735 3835);
FORCEPROP 2 LASTPROP $XRERR UNIQUE?
J 0
(-6975 3835);
DISPLAY 0.638298 (-6975 3835);
PAINT MONO (-6975 3835);
DISPLAY INVISIBLE (-6975 3835);
WIRE 16 -1 (-6150 3725)(-6850 3725);
WIRE 16 -1 (-6175 2775)(-6175 2675);
WIRE 16 -1 (-6175 2775)(-6875 2775);
FORCEPROP 0 LAST CDS_PHYS_NET_NAME TDR_SE_50_OHM_IN6
J 0
(-6835 2815);
PAINT MONO (-6835 2815);
DISPLAY INVISIBLE (-6835 2815);
FORCEPROP 2 LAST SIG_NAME TDR_SE_50_OHM_IN6
J 0
(-6760 2785);
DISPLAY 0.638298 (-6760 2785);
PAINT WHITE (-6760 2785);
FORCEPROP 2 LASTPROP $XRERR UNIQUE?
J 0
(-7000 2785);
DISPLAY 0.638298 (-7000 2785);
PAINT MONO (-7000 2785);
DISPLAY INVISIBLE (-7000 2785);
WIRE 16 -1 (-6175 2675)(-6875 2675);
WIRE 16 -1 (-7850 3825)(-7850 3725);
WIRE 16 -1 (-7850 3825)(-8550 3825);
FORCEPROP 0 LAST CDS_PHYS_NET_NAME TDR_SE_45_OHM_IN4
J 0
(-8510 3865);
PAINT MONO (-8510 3865);
DISPLAY INVISIBLE (-8510 3865);
FORCEPROP 2 LAST SIG_NAME TDR_SE_45_OHM_IN4
J 0
(-8435 3835);
DISPLAY 0.638298 (-8435 3835);
PAINT WHITE (-8435 3835);
FORCEPROP 2 LASTPROP $XRERR UNIQUE?
J 0
(-8675 3835);
DISPLAY 0.638298 (-8675 3835);
PAINT MONO (-8675 3835);
DISPLAY INVISIBLE (-8675 3835);
WIRE 16 -1 (-7850 3725)(-8550 3725);
WIRE 16 -1 (-7875 3300)(-7875 3200);
WIRE 16 -1 (-7875 3300)(-8575 3300);
FORCEPROP 0 LAST CDS_PHYS_NET_NAME TDR_SE_45_OHM_IN5
J 0
(-8535 3340);
PAINT MONO (-8535 3340);
DISPLAY INVISIBLE (-8535 3340);
FORCEPROP 2 LAST SIG_NAME TDR_SE_45_OHM_IN5
J 0
(-8460 3310);
DISPLAY 0.638298 (-8460 3310);
PAINT WHITE (-8460 3310);
FORCEPROP 2 LASTPROP $XRERR UNIQUE?
J 0
(-8700 3310);
DISPLAY 0.638298 (-8700 3310);
PAINT MONO (-8700 3310);
DISPLAY INVISIBLE (-8700 3310);
WIRE 16 -1 (-7875 3200)(-8575 3200);
WIRE 16 -1 (-7900 2225)(-7900 2125);
WIRE 16 -1 (-7900 2225)(-8600 2225);
FORCEPROP 0 LAST CDS_PHYS_NET_NAME TDR_SE_45_OHM_BOT
J 0
(-8560 2265);
PAINT MONO (-8560 2265);
DISPLAY INVISIBLE (-8560 2265);
FORCEPROP 2 LAST SIG_NAME TDR_SE_45_OHM_BOT
J 0
(-8485 2235);
DISPLAY 0.638298 (-8485 2235);
PAINT WHITE (-8485 2235);
FORCEPROP 2 LASTPROP $XRERR UNIQUE?
J 0
(-8725 2235);
DISPLAY 0.638298 (-8725 2235);
PAINT MONO (-8725 2235);
DISPLAY INVISIBLE (-8725 2235);
WIRE 16 -1 (-7900 2125)(-8600 2125);
WIRE 16 -1 (-7875 2775)(-7875 2675);
WIRE 16 -1 (-7875 2775)(-8575 2775);
FORCEPROP 0 LAST CDS_PHYS_NET_NAME TDR_SE_45_OHM_IN6
J 0
(-8535 2815);
PAINT MONO (-8535 2815);
DISPLAY INVISIBLE (-8535 2815);
FORCEPROP 2 LAST SIG_NAME TDR_SE_45_OHM_IN6
J 0
(-8460 2785);
DISPLAY 0.638298 (-8460 2785);
PAINT WHITE (-8460 2785);
FORCEPROP 2 LASTPROP $XRERR UNIQUE?
J 0
(-8700 2785);
DISPLAY 0.638298 (-8700 2785);
PAINT MONO (-8700 2785);
DISPLAY INVISIBLE (-8700 2785);
WIRE 16 -1 (-7875 2675)(-8575 2675);
WIRE 16 -1 (-7850 4350)(-7850 4250);
WIRE 16 -1 (-7850 4350)(-8550 4350);
FORCEPROP 0 LAST CDS_PHYS_NET_NAME TDR_SE_45_OHM_IN3
J 0
(-8510 4390);
PAINT MONO (-8510 4390);
DISPLAY INVISIBLE (-8510 4390);
FORCEPROP 2 LAST SIG_NAME TDR_SE_45_OHM_IN3
J 0
(-8435 4360);
DISPLAY 0.638298 (-8435 4360);
PAINT WHITE (-8435 4360);
FORCEPROP 2 LASTPROP $XRERR UNIQUE?
J 0
(-8675 4360);
DISPLAY 0.638298 (-8675 4360);
PAINT MONO (-8675 4360);
DISPLAY INVISIBLE (-8675 4360);
WIRE 16 -1 (-7850 4250)(-8550 4250);
WIRE 16 -1 (-7850 5400)(-7850 5300);
WIRE 16 -1 (-7850 5400)(-8550 5400);
FORCEPROP 0 LAST CDS_PHYS_NET_NAME TDR_SE_45_OHM_IN1
J 0
(-8510 5440);
PAINT MONO (-8510 5440);
DISPLAY INVISIBLE (-8510 5440);
FORCEPROP 2 LAST SIG_NAME TDR_SE_45_OHM_IN1
J 0
(-8435 5410);
DISPLAY 0.638298 (-8435 5410);
PAINT WHITE (-8435 5410);
FORCEPROP 2 LASTPROP $XRERR UNIQUE?
J 0
(-8675 5410);
DISPLAY 0.638298 (-8675 5410);
PAINT MONO (-8675 5410);
DISPLAY INVISIBLE (-8675 5410);
WIRE 16 -1 (-7850 5300)(-8550 5300);
WIRE 16 -1 (-7850 5925)(-7850 5825);
WIRE 16 -1 (-7850 5925)(-8550 5925);
FORCEPROP 0 LAST CDS_PHYS_NET_NAME TDR_SE_45_OHM_TOP
J 0
(-8510 5965);
PAINT MONO (-8510 5965);
DISPLAY INVISIBLE (-8510 5965);
FORCEPROP 2 LAST SIG_NAME TDR_SE_45_OHM_TOP
J 0
(-8435 5935);
DISPLAY 0.638298 (-8435 5935);
PAINT WHITE (-8435 5935);
FORCEPROP 2 LASTPROP $XRERR UNIQUE?
J 0
(-8675 5935);
DISPLAY 0.638298 (-8675 5935);
PAINT MONO (-8675 5935);
DISPLAY INVISIBLE (-8675 5935);
WIRE 16 -1 (-7850 5825)(-8550 5825);
WIRE 16 -1 (-7850 4875)(-7850 4775);
WIRE 16 -1 (-7850 4875)(-8550 4875);
FORCEPROP 0 LAST CDS_PHYS_NET_NAME TDR_SE_45_OHM_IN2
J 0
(-8510 4915);
PAINT MONO (-8510 4915);
DISPLAY INVISIBLE (-8510 4915);
FORCEPROP 2 LAST SIG_NAME TDR_SE_45_OHM_IN2
J 0
(-8435 4885);
DISPLAY 0.638298 (-8435 4885);
PAINT WHITE (-8435 4885);
FORCEPROP 2 LASTPROP $XRERR UNIQUE?
J 0
(-8675 4885);
DISPLAY 0.638298 (-8675 4885);
PAINT MONO (-8675 4885);
DISPLAY INVISIBLE (-8675 4885);
WIRE 16 -1 (-7850 4775)(-8550 4775);
WIRE 16 -1 (-9050 2175)(-8900 2175);
WIRE 16 -1 (-9050 2000)(-9050 2175);
WIRE 16 -1 (-9000 4825)(-8850 4825);
WIRE 16 -1 (-9000 4650)(-9000 4825);
WIRE 16 -1 (-9000 5350)(-8850 5350);
WIRE 16 -1 (-9000 5175)(-9000 5350);
WIRE 16 -1 (-9000 5875)(-8850 5875);
WIRE 16 -1 (-9000 5700)(-9000 5875);
WIRE 16 -1 (-7350 2175)(-7200 2175);
WIRE 16 -1 (-7350 2000)(-7350 2175);
WIRE 16 -1 (-7325 2725)(-7175 2725);
WIRE 16 -1 (-7325 2550)(-7325 2725);
WIRE 16 -1 (-7325 3250)(-7175 3250);
WIRE 16 -1 (-7325 3075)(-7325 3250);
WIRE 16 -1 (-7300 3775)(-7150 3775);
WIRE 16 -1 (-7300 3600)(-7300 3775);
WIRE 16 -1 (-7300 4300)(-7150 4300);
WIRE 16 -1 (-7300 4125)(-7300 4300);
WIRE 16 -1 (-5450 700)(-5300 700);
WIRE 16 -1 (-5450 700)(-5450 550);
WIRE 16 -1 (-5450 550)(-5300 550);
WIRE 16 -1 (-5450 475)(-5450 550);
WIRE 16 -1 (-5450 1200)(-5300 1200);
WIRE 16 -1 (-5450 1200)(-5450 1350);
WIRE 16 -1 (-5450 1100)(-5450 1200);
WIRE 16 -1 (-5450 1350)(-5300 1350);
WIRE 16 -1 (-5450 1975)(-5450 2125);
WIRE 16 -1 (-5450 1975)(-5300 1975);
WIRE 16 -1 (-5450 1875)(-5450 1975);
WIRE 16 -1 (-5450 2125)(-5300 2125);
WIRE 16 -1 (-9025 2725)(-8875 2725);
WIRE 16 -1 (-9025 2550)(-9025 2725);
WIRE 16 -1 (-5450 2650)(-5300 2650);
WIRE 16 -1 (-5450 2650)(-5450 2800);
WIRE 16 -1 (-5450 2550)(-5450 2650);
WIRE 16 -1 (-5450 2800)(-5300 2800);
WIRE 16 -1 (-5450 3425)(-5300 3425);
WIRE 16 -1 (-5450 3425)(-5450 3575);
WIRE 16 -1 (-5450 3325)(-5450 3425);
WIRE 16 -1 (-5450 3575)(-5300 3575);
WIRE 16 -1 (-5450 4200)(-5300 4200);
WIRE 16 -1 (-5450 4200)(-5450 4350);
WIRE 16 -1 (-5450 4100)(-5450 4200);
WIRE 16 -1 (-5450 4350)(-5300 4350);
WIRE 16 -1 (-7300 4825)(-7150 4825);
WIRE 16 -1 (-7300 4650)(-7300 4825);
WIRE 16 -1 (-9025 3250)(-8875 3250);
WIRE 16 -1 (-9025 3075)(-9025 3250);
WIRE 16 -1 (-7300 5350)(-7150 5350);
WIRE 16 -1 (-7300 5175)(-7300 5350);
WIRE 16 -1 (-7300 5875)(-7150 5875);
WIRE 16 -1 (-7300 5700)(-7300 5875);
WIRE 16 -1 (-5450 4975)(-5450 5125);
WIRE 16 -1 (-5450 4975)(-5300 4975);
WIRE 16 -1 (-5450 4875)(-5450 4975);
WIRE 16 -1 (-5450 5125)(-5300 5125);
WIRE 16 -1 (-5450 5750)(-5300 5750);
WIRE 16 -1 (-5450 5750)(-5450 5900);
WIRE 16 -1 (-5450 5650)(-5450 5750);
WIRE 16 -1 (-5450 5900)(-5300 5900);
WIRE 16 -1 (-3300 700)(-3300 550);
WIRE 16 -1 (-3300 700)(-3425 700);
WIRE 16 -1 (-3425 550)(-3300 550);
WIRE 16 -1 (-3300 475)(-3300 550);
WIRE 16 -1 (-3300 1200)(-3300 1350);
WIRE 16 -1 (-3300 1100)(-3300 1200);
WIRE 16 -1 (-3425 1200)(-3300 1200);
WIRE 16 -1 (-3300 1350)(-3425 1350);
WIRE 16 -1 (-3425 1975)(-3300 1975);
WIRE 16 -1 (-3300 1975)(-3300 2125);
WIRE 16 -1 (-3300 1875)(-3300 1975);
WIRE 16 -1 (-3300 2125)(-3425 2125);
WIRE 16 -1 (-2625 725)(-2475 725);
WIRE 16 -1 (-2625 725)(-2625 575);
WIRE 16 -1 (-2625 575)(-2475 575);
WIRE 16 -1 (-2625 500)(-2625 575);
WIRE 16 -1 (-2625 1225)(-2475 1225);
WIRE 16 -1 (-2625 1225)(-2625 1375);
WIRE 16 -1 (-2625 1125)(-2625 1225);
WIRE 16 -1 (-2625 1375)(-2475 1375);
WIRE 16 -1 (-2625 2000)(-2625 2150);
WIRE 16 -1 (-2625 2000)(-2475 2000);
WIRE 16 -1 (-2625 1900)(-2625 2000);
WIRE 16 -1 (-2625 2150)(-2475 2150);
WIRE 16 -1 (-9000 3775)(-8850 3775);
WIRE 16 -1 (-9000 3600)(-9000 3775);
WIRE 16 -1 (-3300 3425)(-3300 3575);
WIRE 16 -1 (-3300 3325)(-3300 3425);
WIRE 16 -1 (-3425 3425)(-3300 3425);
WIRE 16 -1 (-3300 3575)(-3425 3575);
WIRE 16 -1 (-3300 4200)(-3300 4350);
WIRE 16 -1 (-3300 4100)(-3300 4200);
WIRE 16 -1 (-3425 4200)(-3300 4200);
WIRE 16 -1 (-3300 4350)(-3425 4350);
WIRE 16 -1 (-2625 2675)(-2475 2675);
WIRE 16 -1 (-2625 2675)(-2625 2825);
WIRE 16 -1 (-2625 2575)(-2625 2675);
WIRE 16 -1 (-2625 2825)(-2475 2825);
WIRE 16 -1 (-2625 3450)(-2475 3450);
WIRE 16 -1 (-2625 3450)(-2625 3600);
WIRE 16 -1 (-2625 3350)(-2625 3450);
WIRE 16 -1 (-2625 3600)(-2475 3600);
WIRE 16 -1 (-2625 4225)(-2475 4225);
WIRE 16 -1 (-2625 4225)(-2625 4375);
WIRE 16 -1 (-2625 4125)(-2625 4225);
WIRE 16 -1 (-2625 4375)(-2475 4375);
WIRE 16 -1 (-9000 4300)(-8850 4300);
WIRE 16 -1 (-9000 4125)(-9000 4300);
WIRE 16 -1 (-475 725)(-475 575);
WIRE 16 -1 (-475 725)(-600 725);
WIRE 16 -1 (-475 500)(-475 575);
WIRE 16 -1 (-600 575)(-475 575);
WIRE 16 -1 (-475 1225)(-475 1375);
WIRE 16 -1 (-475 1125)(-475 1225);
WIRE 16 -1 (-600 1225)(-475 1225);
WIRE 16 -1 (-475 1375)(-600 1375);
WIRE 16 -1 (-600 2000)(-475 2000);
WIRE 16 -1 (-475 2000)(-475 2150);
WIRE 16 -1 (-475 1900)(-475 2000);
WIRE 16 -1 (-475 2150)(-600 2150);
WIRE 16 -1 (-475 2675)(-475 2825);
WIRE 16 -1 (-475 2575)(-475 2675);
WIRE 16 -1 (-600 2675)(-475 2675);
WIRE 16 -1 (-475 2825)(-600 2825);
WIRE 16 -1 (-475 3450)(-475 3600);
WIRE 16 -1 (-475 3350)(-475 3450);
WIRE 16 -1 (-600 3450)(-475 3450);
WIRE 16 -1 (-475 3600)(-600 3600);
WIRE 16 -1 (-475 4225)(-475 4375);
WIRE 16 -1 (-475 4125)(-475 4225);
WIRE 16 -1 (-600 4225)(-475 4225);
WIRE 16 -1 (-475 4375)(-600 4375);
WIRE 16 -1 (-3425 4975)(-3300 4975);
WIRE 16 -1 (-3300 4975)(-3300 5125);
WIRE 16 -1 (-3300 4875)(-3300 4975);
WIRE 16 -1 (-3300 5125)(-3425 5125);
WIRE 16 -1 (-3300 5750)(-3300 5900);
WIRE 16 -1 (-3300 5650)(-3300 5750);
WIRE 16 -1 (-3425 5750)(-3300 5750);
WIRE 16 -1 (-3300 5900)(-3425 5900);
WIRE 16 -1 (-2625 5000)(-2625 5150);
WIRE 16 -1 (-2625 5000)(-2475 5000);
WIRE 16 -1 (-2625 4900)(-2625 5000);
WIRE 16 -1 (-2625 5150)(-2475 5150);
WIRE 16 -1 (-2625 5775)(-2475 5775);
WIRE 16 -1 (-2625 5775)(-2625 5925);
WIRE 16 -1 (-2625 5675)(-2625 5775);
WIRE 16 -1 (-2625 5925)(-2475 5925);
WIRE 16 -1 (-600 5000)(-475 5000);
WIRE 16 -1 (-475 5000)(-475 5150);
WIRE 16 -1 (-475 4900)(-475 5000);
WIRE 16 -1 (-475 5150)(-600 5150);
WIRE 16 -1 (-475 5775)(-475 5925);
WIRE 16 -1 (-475 5675)(-475 5775);
WIRE 16 -1 (-600 5775)(-475 5775);
WIRE 16 -1 (-475 5925)(-600 5925);
WIRE 16 -1 (-3300 2650)(-3300 2800);
WIRE 16 -1 (-3425 2650)(-3300 2650);
WIRE 16 -1 (-3300 2550)(-3300 2650);
WIRE 16 -1 (-3300 2800)(-3425 2800);
DOT 1 (-5450 550);
DOT 1 (-5450 1200);
DOT 1 (-5450 1975);
DOT 1 (-5450 2650);
DOT 1 (-5450 3425);
DOT 1 (-5450 4200);
DOT 1 (-5450 4975);
DOT 1 (-5450 5750);
DOT 1 (-3300 550);
DOT 1 (-3300 1200);
DOT 1 (-3300 1975);
DOT 1 (-2625 575);
DOT 1 (-2625 1225);
DOT 1 (-2625 2000);
DOT 1 (-3300 2650);
DOT 1 (-3300 3425);
DOT 1 (-2625 2675);
DOT 1 (-2625 3450);
DOT 1 (-475 575);
DOT 1 (-475 1225);
DOT 1 (-475 2000);
DOT 1 (-475 2675);
DOT 1 (-475 3450);
DOT 1 (-3300 4200);
DOT 1 (-3300 4975);
DOT 1 (-3300 5750);
DOT 1 (-2625 4225);
DOT 1 (-2625 5000);
DOT 1 (-2625 5775);
DOT 1 (-475 4225);
DOT 1 (-475 5000);
DOT 1 (-475 5775);
FORCENOTE
45 OHM
(-8900 6400) 0;
DISPLAY LEFT (-8900 6400);
DISPLAY 3.148936 (-8900 6400);
PAINT WHITE (-8900 6400);
FORCENOTE
50 OHM
(-7225 6400) 0;
DISPLAY LEFT (-7225 6400);
DISPLAY 3.148936 (-7225 6400);
PAINT WHITE (-7225 6400);
FORCENOTE
80 OHM
(-4800 6350) 0;
DISPLAY LEFT (-4800 6350);
DISPLAY 3.148936 (-4800 6350);
PAINT WHITE (-4800 6350);
FORCENOTE
85 OHM
(-1975 6375) 0;
DISPLAY LEFT (-1975 6375);
DISPLAY 3.148936 (-1975 6375);
PAINT WHITE (-1975 6375);
QUIT
